FILE_TYPE = MACRO_DRAWING;
SET COLOR_WIRE YELLOW;
SET COLOR_PROP MONO;
SET COLOR_DOT WHITE;
SET COLOR_ARC YELLOW;
SET COLOR_BODY GREEN;
SET COLOR_NOTE MONO;
SET PROP_DISPLAY VALUE;
SET PAGE_NUMBER P197;
FORCEADD P12V_NVDIMM_ABC..1
(-4875 4925);
FORCEPROP 3 LASTPIN (-4875 4875) SIG_NAME P12V_NVDIMM_ABC\g
J 0
(-4865 4885);
DISPLAY 0.659574 (-4865 4885);
PAINT MONO (-4865 4885);
DISPLAY INVISIBLE (-4865 4885);
FORCEPROP 1 LAST VOLTAGE 12.0
J 0
(-4920 4882);
DISPLAY 0.340426 (-4920 4882);
PAINT SKYBLUE (-4920 4882);
DISPLAY INVISIBLE (-4920 4882);
FORCEPROP 2 LAST CDS_LIB mstr_symbols
J 0
(-4875 4925);
PAINT ORANGE (-4875 4925);
DISPLAY INVISIBLE (-4875 4925);
FORCEPROP 1 LAST BODY_TYPE PLUMBING
J 0
(-4920 4882);
DISPLAY 0.340426 (-4920 4882);
PAINT GREEN (-4920 4882);
DISPLAY INVISIBLE (-4920 4882);
FORCEPROP 1 LAST PATH I101
J 0
(-4825 4950);
DISPLAY 0.872340 (-4825 4950);
PAINT AQUA (-4825 4950);
DISPLAY INVISIBLE (-4825 4950);
FORCEPROP 1 LAST HDL_POWER P12V_NVDIMM_ABC
J 1
(-4875 4950);
DISPLAY 0.872340 (-4875 4950);
PAINT GREEN (-4875 4950);
DISPLAY INVISIBLE (-4875 4950);
FORCEADD GND..1
(-3250 4150);
FORCEPROP 3 LASTPIN (-3250 4200) SIG_NAME GND\g
J 0
(-3240 4210);
DISPLAY 0.659574 (-3240 4210);
PAINT MONO (-3240 4210);
DISPLAY INVISIBLE (-3240 4210);
FORCEPROP 1 LAST VOLTAGE 0.0V
J 0
(-3295 4107);
DISPLAY 0.340426 (-3295 4107);
PAINT SKYBLUE (-3295 4107);
DISPLAY INVISIBLE (-3295 4107);
FORCEPROP 1 LAST SIZE 1B
J 0
(-3175 4100);
DISPLAY 1.170213 (-3175 4100);
PAINT AQUA (-3175 4100);
DISPLAY INVISIBLE (-3175 4100);
FORCEPROP 2 LAST CDS_LIB mstr_symbols
J 0
(-3250 4150);
PAINT ORANGE (-3250 4150);
DISPLAY INVISIBLE (-3250 4150);
FORCEPROP 1 LAST BODY_TYPE PLUMBING
J 0
(-3295 4107);
DISPLAY 0.340426 (-3295 4107);
PAINT GREEN (-3295 4107);
DISPLAY INVISIBLE (-3295 4107);
FORCEPROP 1 LAST PATH I103
J 0
(-3175 4150);
DISPLAY 0.872340 (-3175 4150);
PAINT AQUA (-3175 4150);
DISPLAY INVISIBLE (-3175 4150);
FORCEPROP 1 LAST HDL_POWER GND
J 0
(-3250 4300);
DISPLAY 1.170213 (-3250 4300);
PAINT GREEN (-3250 4300);
DISPLAY INVISIBLE (-3250 4300);
FORCEADD RES..1
(-2775 4475);
FORCEPROP 1 LAST LOCATION R4F1
J 0
(-2825 4525);
DISPLAY 0.617021 (-2825 4525);
PAINT AQUA (-2825 4525);
FORCEPROP 1 LAST PART_NUMBER G21497-005
J 0
(-2825 4575);
DISPLAY 0.617021 (-2825 4575);
PAINT BLUE (-2825 4575);
FORCEPROP 1 LAST VALUE 0.0
J 2
(-2875 4400);
DISPLAY 0.617021 (-2875 4400);
PAINT SKYBLUE (-2875 4400);
FORCEPROP 1 LAST TOLERANCE 5%
J 0
(-2825 4400);
DISPLAY 0.617021 (-2825 4400);
PAINT SKYBLUE (-2825 4400);
FORCEPROP 1 LAST PACK_TYPE 0402
J 0
(-2975 4275);
DISPLAY 0.617021 (-2975 4275);
PAINT SKYBLUE (-2975 4275);
FORCEPROP 1 LAST MATERIAL CHIP
J 0
(-2875 4350);
DISPLAY 0.617021 (-2875 4350);
PAINT SKYBLUE (-2875 4350);
FORCEPROP 1 LAST WATTAGE 1/16W
J 2
(-2575 4400);
DISPLAY 0.617021 (-2575 4400);
PAINT SKYBLUE (-2575 4400);
FORCEPROP 1 LASTPIN (-2675 4475) $PN 2
J 0
(-2713 4487);
DISPLAY 0.617021 (-2713 4487);
PAINT ORANGE (-2713 4487);
FORCEPROP 1 LASTPIN (-2875 4475) $PN 1
J 0
(-2863 4487);
DISPLAY 0.617021 (-2863 4487);
PAINT ORANGE (-2863 4487);
FORCEPROP 2 LAST SEC_TYPE 0402
J 0
(-2825 4675);
DISPLAY 1.021277 (-2825 4675);
PAINT ORANGE (-2825 4675);
DISPLAY INVISIBLE (-2825 4675);
FORCEPROP 2 LAST CDS_LIB mstr_discrete
J 0
(-2775 4475);
PAINT ORANGE (-2775 4475);
DISPLAY INVISIBLE (-2775 4475);
FORCEPROP 2 LAST BOM_COST PVDDQ_ABC_VR
J 0
(-2825 4725);
DISPLAY 1.361702 (-2825 4725);
PAINT ORANGE (-2825 4725);
DISPLAY INVISIBLE (-2825 4725);
FORCEPROP 2 LAST SEC 1
J 0
(-2825 4675);
DISPLAY 0.680851 (-2825 4675);
PAINT MONO (-2825 4675);
DISPLAY INVISIBLE (-2825 4675);
FORCEPROP 2 LAST CDS_LOCATION R4F1
J 0
(-2825 4525);
DISPLAY 0.617021 (-2825 4525);
PAINT AQUA (-2825 4525);
DISPLAY INVISIBLE (-2825 4525);
FORCEPROP 1 LAST PATH I110
J 0
(-2825 4625);
DISPLAY 0.978723 (-2825 4625);
PAINT WHITE (-2825 4625);
DISPLAY INVISIBLE (-2825 4625);
FORCEPROP 2 LAST ROOM PVDDQ_ABC_PWR_VR
J 0
(-2825 4625);
DISPLAY 1.361702 (-2825 4625);
PAINT ORANGE (-2825 4625);
DISPLAY INVISIBLE (-2825 4625);
FORCEADD OFFPAGE..5
R 2
(-1875 4475);
FORCEPROP 2 LAST $XR0 215 
J 0
(-1686 4475);
DISPLAY 0.638298 (-1686 4475);
PAINT MONO (-1686 4475);
FORCEPROP 2 LAST CDS_LIB mstr_standard
J 2
(-1875 4475);
PAINT ORANGE (-1875 4475);
DISPLAY INVISIBLE (-1875 4475);
FORCEPROP 1 LAST OFFPAGE TRUE
J 2
(-2200 4350);
DISPLAY 1.170213 (-2200 4350);
PAINT GREEN (-2200 4350);
DISPLAY INVISIBLE (-2200 4350);
FORCEPROP 1 LAST COMMENT_BODY TRUE
J 2
(-1975 4400);
DISPLAY 1.170213 (-1975 4400);
PAINT GREEN (-1975 4400);
DISPLAY INVISIBLE (-1975 4400);
FORCEPROP 2 LAST PATH I111
J 2
(-1925 4550);
DISPLAY 1.021277 (-1925 4550);
PAINT ORANGE (-1925 4550);
DISPLAY INVISIBLE (-1925 4550);
FORCEADD OFFPAGE..5
R 2
(-1875 3025);
FORCEPROP 2 LAST $XR0 218 
J 0
(-1686 3025);
DISPLAY 0.638298 (-1686 3025);
PAINT MONO (-1686 3025);
FORCEPROP 2 LAST CDS_LIB mstr_standard
J 0
(-1875 3025);
PAINT ORANGE (-1875 3025);
DISPLAY INVISIBLE (-1875 3025);
FORCEPROP 1 LAST OFFPAGE TRUE
J 2
(-2200 2900);
DISPLAY 1.170213 (-2200 2900);
PAINT GREEN (-2200 2900);
DISPLAY INVISIBLE (-2200 2900);
FORCEPROP 1 LAST COMMENT_BODY TRUE
J 2
(-1975 2950);
DISPLAY 1.170213 (-1975 2950);
PAINT GREEN (-1975 2950);
DISPLAY INVISIBLE (-1975 2950);
FORCEPROP 2 LAST PATH I112
J 0
(-1700 3100);
DISPLAY 1.021277 (-1700 3100);
PAINT ORANGE (-1700 3100);
DISPLAY INVISIBLE (-1700 3100);
FORCEADD RES..1
(-2775 3025);
FORCEPROP 1 LAST LOCATION R4B11
J 0
(-2825 3075);
DISPLAY 0.617021 (-2825 3075);
PAINT AQUA (-2825 3075);
FORCEPROP 1 LAST PART_NUMBER G21497-005
J 0
(-2825 3125);
DISPLAY 0.617021 (-2825 3125);
PAINT BLUE (-2825 3125);
FORCEPROP 1 LAST VALUE 0.0
J 2
(-2875 2950);
DISPLAY 0.617021 (-2875 2950);
PAINT SKYBLUE (-2875 2950);
FORCEPROP 1 LAST TOLERANCE 5%
J 0
(-2825 2950);
DISPLAY 0.617021 (-2825 2950);
PAINT SKYBLUE (-2825 2950);
FORCEPROP 1 LAST PACK_TYPE 0402
J 0
(-2975 2825);
DISPLAY 0.617021 (-2975 2825);
PAINT SKYBLUE (-2975 2825);
FORCEPROP 1 LAST MATERIAL CHIP
J 0
(-2875 2900);
DISPLAY 0.617021 (-2875 2900);
PAINT SKYBLUE (-2875 2900);
FORCEPROP 1 LAST WATTAGE 1/16W
J 2
(-2575 2950);
DISPLAY 0.617021 (-2575 2950);
PAINT SKYBLUE (-2575 2950);
FORCEPROP 1 LASTPIN (-2675 3025) $PN 2
J 0
(-2713 3037);
DISPLAY 0.617021 (-2713 3037);
PAINT ORANGE (-2713 3037);
FORCEPROP 1 LASTPIN (-2875 3025) $PN 1
J 0
(-2863 3037);
DISPLAY 0.617021 (-2863 3037);
PAINT ORANGE (-2863 3037);
FORCEPROP 2 LAST SEC_TYPE 0402
J 0
(-2825 3225);
DISPLAY 1.021277 (-2825 3225);
PAINT ORANGE (-2825 3225);
DISPLAY INVISIBLE (-2825 3225);
FORCEPROP 2 LAST CDS_LIB mstr_discrete
J 0
(-2775 3025);
PAINT ORANGE (-2775 3025);
DISPLAY INVISIBLE (-2775 3025);
FORCEPROP 2 LAST BOM_COST PVDDQ_DEF_VR
J 0
(-2825 3275);
DISPLAY 1.361702 (-2825 3275);
PAINT ORANGE (-2825 3275);
DISPLAY INVISIBLE (-2825 3275);
FORCEPROP 2 LAST SEC 1
J 0
(-2825 3225);
DISPLAY 0.680851 (-2825 3225);
PAINT MONO (-2825 3225);
DISPLAY INVISIBLE (-2825 3225);
FORCEPROP 2 LAST CDS_LOCATION R4B11
J 0
(-2825 3075);
DISPLAY 0.617021 (-2825 3075);
PAINT AQUA (-2825 3075);
DISPLAY INVISIBLE (-2825 3075);
FORCEPROP 1 LAST PATH I113
J 0
(-2825 3175);
DISPLAY 0.978723 (-2825 3175);
PAINT WHITE (-2825 3175);
DISPLAY INVISIBLE (-2825 3175);
FORCEPROP 2 LAST ROOM PVDDQ_DEF_PWR_VR
J 0
(-2825 3175);
DISPLAY 1.361702 (-2825 3175);
PAINT ORANGE (-2825 3175);
DISPLAY INVISIBLE (-2825 3175);
FORCEADD GND..1
(-3250 2700);
FORCEPROP 3 LASTPIN (-3250 2750) SIG_NAME GND\g
J 0
(-3240 2760);
DISPLAY 0.659574 (-3240 2760);
PAINT MONO (-3240 2760);
DISPLAY INVISIBLE (-3240 2760);
FORCEPROP 1 LAST VOLTAGE 0.0V
J 0
(-3295 2657);
DISPLAY 0.340426 (-3295 2657);
PAINT SKYBLUE (-3295 2657);
DISPLAY INVISIBLE (-3295 2657);
FORCEPROP 2 LAST CDS_LIB mstr_symbols
J 0
(-3250 2700);
PAINT ORANGE (-3250 2700);
DISPLAY INVISIBLE (-3250 2700);
FORCEPROP 1 LAST SIZE 1B
J 0
(-3175 2650);
DISPLAY 1.170213 (-3175 2650);
PAINT AQUA (-3175 2650);
DISPLAY INVISIBLE (-3175 2650);
FORCEPROP 1 LAST BODY_TYPE PLUMBING
J 0
(-3295 2657);
DISPLAY 0.340426 (-3295 2657);
PAINT GREEN (-3295 2657);
DISPLAY INVISIBLE (-3295 2657);
FORCEPROP 1 LAST PATH I114
J 0
(-3175 2700);
DISPLAY 0.872340 (-3175 2700);
PAINT AQUA (-3175 2700);
DISPLAY INVISIBLE (-3175 2700);
FORCEPROP 1 LAST HDL_POWER GND
J 0
(-3250 2850);
DISPLAY 1.170213 (-3250 2850);
PAINT GREEN (-3250 2850);
DISPLAY INVISIBLE (-3250 2850);
FORCEADD MAX9634..1
(-3800 2975);
FORCEPROP 1 LAST LOCATION U4B1
J 0
(-4150 3325);
DISPLAY 0.617021 (-4150 3325);
PAINT AQUA (-4150 3325);
FORCEPROP 1 LAST PART_NUMBER H35789-001
J 0
(-4150 2675);
DISPLAY 0.617021 (-4150 2675);
PAINT BLUE (-4150 2675);
FORCEPROP 1 LAST MATERIAL IC
J 0
(-4150 3275);
DISPLAY 0.617021 (-4150 3275);
PAINT SKYBLUE (-4150 3275);
FORCEPROP 2 LASTPIN (-4200 3025) $PN 5
J 2
(-4210 3035);
DISPLAY 0.617021 (-4210 3035);
PAINT ORANGE (-4210 3035);
FORCEPROP 2 LASTPIN (-4200 2975) $PN 4
J 2
(-4210 2985);
DISPLAY 0.617021 (-4210 2985);
PAINT ORANGE (-4210 2985);
FORCEPROP 2 LASTPIN (-3400 3025) $PN 3
J 0
(-3390 3035);
DISPLAY 0.617021 (-3390 3035);
PAINT ORANGE (-3390 3035);
FORCEPROP 2 LASTPIN (-3400 2925) $PN 1
J 0
(-3390 2935);
DISPLAY 0.617021 (-3390 2935);
PAINT ORANGE (-3390 2935);
FORCEPROP 2 LASTPIN (-3400 2875) $PN 2
J 0
(-3390 2885);
DISPLAY 0.617021 (-3390 2885);
PAINT ORANGE (-3390 2885);
FORCEPROP 1 LAST PACK_TYPE SOT
J 0
(-4150 3375);
PAINT SKYBLUE (-4150 3375);
DISPLAY INVISIBLE (-4150 3375);
FORCEPROP 2 LAST SEC_TYPE SOT
J 0
(-4150 3375);
DISPLAY 1.021277 (-4150 3375);
PAINT ORANGE (-4150 3375);
DISPLAY INVISIBLE (-4150 3375);
FORCEPROP 0 LAST BOM_COST PVDDQ_DEF_VR
J 0
(-4150 3525);
DISPLAY 1.021277 (-4150 3525);
PAINT ORANGE (-4150 3525);
DISPLAY INVISIBLE (-4150 3525);
FORCEPROP 2 LAST CDS_LIB mstr_vreg
J 0
(-3800 2975);
PAINT ORANGE (-3800 2975);
DISPLAY INVISIBLE (-3800 2975);
FORCEPROP 2 LAST SEC 1
J 0
(-4150 3375);
DISPLAY 0.680851 (-4150 3375);
PAINT MONO (-4150 3375);
DISPLAY INVISIBLE (-4150 3375);
FORCEPROP 2 LAST CDS_LOCATION U4B1
J 0
(-4150 3325);
DISPLAY 0.617021 (-4150 3325);
PAINT AQUA (-4150 3325);
DISPLAY INVISIBLE (-4150 3325);
FORCEPROP 1 LAST PATH I120
J 0
(-3825 3275);
PAINT GREEN (-3825 3275);
DISPLAY INVISIBLE (-3825 3275);
FORCEPROP 2 LAST ROOM PVDDQ_DEF_PWR_VR
J 0
(-4150 3425);
DISPLAY 1.021277 (-4150 3425);
PAINT ORANGE (-4150 3425);
DISPLAY INVISIBLE (-4150 3425);
FORCEADD RES..1
(-4575 3300);
FORCEPROP 1 LAST LOCATION R4B12
J 0
(-4625 3350);
DISPLAY 0.617021 (-4625 3350);
PAINT AQUA (-4625 3350);
FORCEPROP 1 LAST PART_NUMBER G52199-004
J 0
(-4625 3400);
DISPLAY 0.617021 (-4625 3400);
PAINT BLUE (-4625 3400);
FORCEPROP 1 LAST VALUE 0.002
J 2
(-4600 3200);
DISPLAY 0.617021 (-4600 3200);
PAINT SKYBLUE (-4600 3200);
FORCEPROP 1 LAST TOLERANCE 1%
J 0
(-4575 3200);
DISPLAY 0.617021 (-4575 3200);
PAINT SKYBLUE (-4575 3200);
FORCEPROP 1 LAST PACK_TYPE 1206
J 0
(-4450 3150);
DISPLAY 0.617021 (-4450 3150);
PAINT SKYBLUE (-4450 3150);
FORCEPROP 1 LAST MATERIAL CHIP
J 0
(-4575 3150);
DISPLAY 0.617021 (-4575 3150);
PAINT SKYBLUE (-4575 3150);
FORCEPROP 1 LAST WATTAGE 1W
J 2
(-4600 3150);
DISPLAY 0.617021 (-4600 3150);
PAINT SKYBLUE (-4600 3150);
FORCEPROP 1 LASTPIN (-4475 3300) $PN 2
J 0
(-4513 3312);
DISPLAY 0.617021 (-4513 3312);
PAINT ORANGE (-4513 3312);
FORCEPROP 1 LASTPIN (-4675 3300) $PN 1
J 0
(-4663 3312);
DISPLAY 0.617021 (-4663 3312);
PAINT ORANGE (-4663 3312);
FORCEPROP 2 LAST SEC_TYPE 1206
J 0
(-4625 3500);
DISPLAY 1.021277 (-4625 3500);
PAINT ORANGE (-4625 3500);
DISPLAY INVISIBLE (-4625 3500);
FORCEPROP 2 LAST BOM_COST PVDDQ_DEF_VR
J 0
(-4625 3500);
DISPLAY 1.361702 (-4625 3500);
PAINT ORANGE (-4625 3500);
DISPLAY INVISIBLE (-4625 3500);
FORCEPROP 2 LAST CDS_LIB mstr_discrete
J 0
(-4575 3300);
PAINT ORANGE (-4575 3300);
DISPLAY INVISIBLE (-4575 3300);
FORCEPROP 2 LAST SEC 1
J 0
(-4625 3500);
DISPLAY 0.680851 (-4625 3500);
PAINT MONO (-4625 3500);
DISPLAY INVISIBLE (-4625 3500);
FORCEPROP 2 LAST CDS_LOCATION R4B12
J 0
(-4625 3350);
DISPLAY 0.617021 (-4625 3350);
PAINT AQUA (-4625 3350);
DISPLAY INVISIBLE (-4625 3350);
FORCEPROP 1 LAST PATH I121
J 0
(-4625 3450);
DISPLAY 0.978723 (-4625 3450);
PAINT WHITE (-4625 3450);
DISPLAY INVISIBLE (-4625 3450);
FORCEPROP 2 LAST ROOM PVDDQ_DEF_PWR_VR
J 0
(-4625 3400);
DISPLAY 1.361702 (-4625 3400);
PAINT ORANGE (-4625 3400);
DISPLAY INVISIBLE (-4625 3400);
FORCEADD P12V_NVDIMM_DEF..1
(-4875 3475);
FORCEPROP 3 LASTPIN (-4875 3425) SIG_NAME P12V_NVDIMM_DEF\g
J 0
(-4865 3435);
DISPLAY 0.659574 (-4865 3435);
PAINT MONO (-4865 3435);
DISPLAY INVISIBLE (-4865 3435);
FORCEPROP 1 LAST VOLTAGE 12.0
J 0
(-4920 3432);
DISPLAY 0.340426 (-4920 3432);
PAINT SKYBLUE (-4920 3432);
DISPLAY INVISIBLE (-4920 3432);
FORCEPROP 2 LAST CDS_LIB mstr_symbols
J 0
(-4875 3475);
PAINT ORANGE (-4875 3475);
DISPLAY INVISIBLE (-4875 3475);
FORCEPROP 1 LAST BODY_TYPE PLUMBING
J 0
(-4920 3432);
DISPLAY 0.340426 (-4920 3432);
PAINT GREEN (-4920 3432);
DISPLAY INVISIBLE (-4920 3432);
FORCEPROP 1 LAST PATH I122
J 0
(-4825 3500);
DISPLAY 0.872340 (-4825 3500);
PAINT AQUA (-4825 3500);
DISPLAY INVISIBLE (-4825 3500);
FORCEPROP 1 LAST HDL_POWER P12V_NVDIMM_DEF
J 1
(-4875 3525);
DISPLAY 0.872340 (-4875 3525);
PAINT GREEN (-4875 3525);
DISPLAY INVISIBLE (-4875 3525);
FORCEADD OFFPAGE..5
R 2
(-1875 1600);
FORCEPROP 2 LAST $XR0 223 
J 0
(-1686 1600);
DISPLAY 0.638298 (-1686 1600);
PAINT MONO (-1686 1600);
FORCEPROP 2 LAST CDS_LIB mstr_standard
J 0
(-1875 1600);
PAINT ORANGE (-1875 1600);
DISPLAY INVISIBLE (-1875 1600);
FORCEPROP 1 LAST OFFPAGE TRUE
J 2
(-2200 1475);
DISPLAY 1.170213 (-2200 1475);
PAINT GREEN (-2200 1475);
DISPLAY INVISIBLE (-2200 1475);
FORCEPROP 1 LAST COMMENT_BODY TRUE
J 2
(-1975 1525);
DISPLAY 1.170213 (-1975 1525);
PAINT GREEN (-1975 1525);
DISPLAY INVISIBLE (-1975 1525);
FORCEPROP 2 LAST PATH I123
J 0
(-1700 1675);
DISPLAY 1.021277 (-1700 1675);
PAINT ORANGE (-1700 1675);
DISPLAY INVISIBLE (-1700 1675);
FORCEADD RES..1
(-2775 1600);
FORCEPROP 1 LAST LOCATION R9T4
J 0
(-2825 1650);
DISPLAY 0.617021 (-2825 1650);
PAINT AQUA (-2825 1650);
FORCEPROP 1 LAST PART_NUMBER G21497-005
J 0
(-2825 1700);
DISPLAY 0.617021 (-2825 1700);
PAINT BLUE (-2825 1700);
FORCEPROP 1 LAST VALUE 0.0
J 2
(-2875 1525);
DISPLAY 0.617021 (-2875 1525);
PAINT SKYBLUE (-2875 1525);
FORCEPROP 1 LAST TOLERANCE 5%
J 0
(-2825 1525);
DISPLAY 0.617021 (-2825 1525);
PAINT SKYBLUE (-2825 1525);
FORCEPROP 1 LAST PACK_TYPE 0402
J 0
(-2975 1400);
DISPLAY 0.617021 (-2975 1400);
PAINT SKYBLUE (-2975 1400);
FORCEPROP 1 LAST MATERIAL CHIP
J 0
(-2875 1475);
DISPLAY 0.617021 (-2875 1475);
PAINT SKYBLUE (-2875 1475);
FORCEPROP 1 LAST WATTAGE 1/16W
J 2
(-2575 1525);
DISPLAY 0.617021 (-2575 1525);
PAINT SKYBLUE (-2575 1525);
FORCEPROP 1 LASTPIN (-2675 1600) $PN 2
J 0
(-2713 1612);
DISPLAY 0.617021 (-2713 1612);
PAINT ORANGE (-2713 1612);
FORCEPROP 1 LASTPIN (-2875 1600) $PN 1
J 0
(-2863 1612);
DISPLAY 0.617021 (-2863 1612);
PAINT ORANGE (-2863 1612);
FORCEPROP 2 LAST SEC_TYPE 0402
J 0
(-2825 1800);
DISPLAY 1.021277 (-2825 1800);
PAINT ORANGE (-2825 1800);
DISPLAY INVISIBLE (-2825 1800);
FORCEPROP 2 LAST BOM_COST PVDDQ_GHJ_VR
J 0
(-2825 1850);
DISPLAY 1.361702 (-2825 1850);
PAINT ORANGE (-2825 1850);
DISPLAY INVISIBLE (-2825 1850);
FORCEPROP 2 LAST CDS_LIB mstr_discrete
J 0
(-2775 1600);
PAINT ORANGE (-2775 1600);
DISPLAY INVISIBLE (-2775 1600);
FORCEPROP 2 LAST SEC 1
J 0
(-2825 1800);
DISPLAY 0.680851 (-2825 1800);
PAINT MONO (-2825 1800);
DISPLAY INVISIBLE (-2825 1800);
FORCEPROP 2 LAST CDS_LOCATION R9T4
J 0
(-2825 1650);
DISPLAY 0.617021 (-2825 1650);
PAINT AQUA (-2825 1650);
DISPLAY INVISIBLE (-2825 1650);
FORCEPROP 1 LAST PATH I126
J 0
(-2825 1750);
DISPLAY 0.978723 (-2825 1750);
PAINT WHITE (-2825 1750);
DISPLAY INVISIBLE (-2825 1750);
FORCEPROP 2 LAST ROOM PVDDQ_GHJ_PWR_VR
J 0
(-2825 1750);
DISPLAY 1.361702 (-2825 1750);
PAINT ORANGE (-2825 1750);
DISPLAY INVISIBLE (-2825 1750);
FORCEADD GND..1
(-3250 1275);
FORCEPROP 3 LASTPIN (-3250 1325) SIG_NAME GND\g
J 0
(-3240 1335);
DISPLAY 0.659574 (-3240 1335);
PAINT MONO (-3240 1335);
DISPLAY INVISIBLE (-3240 1335);
FORCEPROP 1 LAST VOLTAGE 0.0V
J 0
(-3295 1232);
DISPLAY 0.340426 (-3295 1232);
PAINT SKYBLUE (-3295 1232);
DISPLAY INVISIBLE (-3295 1232);
FORCEPROP 2 LAST CDS_LIB mstr_symbols
J 0
(-3250 1275);
PAINT ORANGE (-3250 1275);
DISPLAY INVISIBLE (-3250 1275);
FORCEPROP 1 LAST SIZE 1B
J 0
(-3175 1225);
DISPLAY 1.170213 (-3175 1225);
PAINT AQUA (-3175 1225);
DISPLAY INVISIBLE (-3175 1225);
FORCEPROP 1 LAST BODY_TYPE PLUMBING
J 0
(-3295 1232);
DISPLAY 0.340426 (-3295 1232);
PAINT GREEN (-3295 1232);
DISPLAY INVISIBLE (-3295 1232);
FORCEPROP 1 LAST PATH I129
J 0
(-3175 1275);
DISPLAY 0.872340 (-3175 1275);
PAINT AQUA (-3175 1275);
DISPLAY INVISIBLE (-3175 1275);
FORCEPROP 1 LAST HDL_POWER GND
J 0
(-3250 1425);
DISPLAY 1.170213 (-3250 1425);
PAINT GREEN (-3250 1425);
DISPLAY INVISIBLE (-3250 1425);
FORCEADD RES..1
(-4575 1875);
FORCEPROP 1 LAST LOCATION R1F3
J 0
(-4625 1925);
DISPLAY 0.617021 (-4625 1925);
PAINT AQUA (-4625 1925);
FORCEPROP 1 LAST PART_NUMBER G52199-004
J 0
(-4625 1975);
DISPLAY 0.617021 (-4625 1975);
PAINT BLUE (-4625 1975);
FORCEPROP 1 LAST VALUE 0.002
J 2
(-4600 1775);
DISPLAY 0.617021 (-4600 1775);
PAINT SKYBLUE (-4600 1775);
FORCEPROP 1 LAST TOLERANCE 1%
J 0
(-4575 1775);
DISPLAY 0.617021 (-4575 1775);
PAINT SKYBLUE (-4575 1775);
FORCEPROP 1 LAST PACK_TYPE 1206
J 0
(-4450 1725);
DISPLAY 0.617021 (-4450 1725);
PAINT SKYBLUE (-4450 1725);
FORCEPROP 1 LAST MATERIAL CHIP
J 0
(-4575 1725);
DISPLAY 0.617021 (-4575 1725);
PAINT SKYBLUE (-4575 1725);
FORCEPROP 1 LAST WATTAGE 1W
J 2
(-4600 1725);
DISPLAY 0.617021 (-4600 1725);
PAINT SKYBLUE (-4600 1725);
FORCEPROP 1 LASTPIN (-4475 1875) $PN 2
J 0
(-4513 1887);
DISPLAY 0.617021 (-4513 1887);
PAINT ORANGE (-4513 1887);
FORCEPROP 1 LASTPIN (-4675 1875) $PN 1
J 0
(-4663 1887);
DISPLAY 0.617021 (-4663 1887);
PAINT ORANGE (-4663 1887);
FORCEPROP 2 LAST SEC_TYPE 1206
J 0
(-4625 2075);
DISPLAY 1.021277 (-4625 2075);
PAINT ORANGE (-4625 2075);
DISPLAY INVISIBLE (-4625 2075);
FORCEPROP 2 LAST CDS_LIB mstr_discrete
J 0
(-4575 1875);
PAINT ORANGE (-4575 1875);
DISPLAY INVISIBLE (-4575 1875);
FORCEPROP 2 LAST BOM_COST PVDDQ_GHJ_VR
J 0
(-4625 2075);
DISPLAY 1.361702 (-4625 2075);
PAINT ORANGE (-4625 2075);
DISPLAY INVISIBLE (-4625 2075);
FORCEPROP 2 LAST SEC 1
J 0
(-4625 2075);
DISPLAY 0.680851 (-4625 2075);
PAINT MONO (-4625 2075);
DISPLAY INVISIBLE (-4625 2075);
FORCEPROP 2 LAST CDS_LOCATION R1F3
J 0
(-4625 1925);
DISPLAY 0.617021 (-4625 1925);
PAINT AQUA (-4625 1925);
DISPLAY INVISIBLE (-4625 1925);
FORCEPROP 1 LAST PATH I131
J 0
(-4625 2025);
DISPLAY 0.978723 (-4625 2025);
PAINT WHITE (-4625 2025);
DISPLAY INVISIBLE (-4625 2025);
FORCEPROP 2 LAST ROOM PVDDQ_GHJ_PWR_VR
J 0
(-4625 1975);
DISPLAY 1.361702 (-4625 1975);
PAINT ORANGE (-4625 1975);
DISPLAY INVISIBLE (-4625 1975);
FORCEADD P12V_NVDIMM_GHJ..1
(-4875 2050);
FORCEPROP 3 LASTPIN (-4875 2000) SIG_NAME P12V_NVDIMM_GHJ\g
J 0
(-4865 2010);
DISPLAY 0.659574 (-4865 2010);
PAINT MONO (-4865 2010);
DISPLAY INVISIBLE (-4865 2010);
FORCEPROP 1 LAST VOLTAGE 12.0
J 0
(-4920 2007);
DISPLAY 0.340426 (-4920 2007);
PAINT SKYBLUE (-4920 2007);
DISPLAY INVISIBLE (-4920 2007);
FORCEPROP 2 LAST CDS_LIB mstr_symbols
J 0
(-4875 2050);
PAINT ORANGE (-4875 2050);
DISPLAY INVISIBLE (-4875 2050);
FORCEPROP 1 LAST BODY_TYPE PLUMBING
J 0
(-4920 2007);
DISPLAY 0.340426 (-4920 2007);
PAINT GREEN (-4920 2007);
DISPLAY INVISIBLE (-4920 2007);
FORCEPROP 1 LAST PATH I132
J 0
(-4825 2075);
DISPLAY 0.872340 (-4825 2075);
PAINT AQUA (-4825 2075);
DISPLAY INVISIBLE (-4825 2075);
FORCEPROP 1 LAST HDL_POWER P12V_NVDIMM_GHJ
J 1
(-4875 2100);
DISPLAY 0.872340 (-4875 2100);
PAINT GREEN (-4875 2100);
DISPLAY INVISIBLE (-4875 2100);
FORCEADD MAX9634..1
(-3800 1550);
FORCEPROP 1 LAST LOCATION U1F1
J 0
(-4150 1900);
DISPLAY 0.617021 (-4150 1900);
PAINT AQUA (-4150 1900);
FORCEPROP 1 LAST PART_NUMBER H35789-001
J 0
(-4150 1250);
DISPLAY 0.617021 (-4150 1250);
PAINT BLUE (-4150 1250);
FORCEPROP 1 LAST MATERIAL IC
J 0
(-4150 1850);
DISPLAY 0.617021 (-4150 1850);
PAINT SKYBLUE (-4150 1850);
FORCEPROP 2 LASTPIN (-4200 1600) $PN 5
J 2
(-4210 1610);
DISPLAY 0.617021 (-4210 1610);
PAINT ORANGE (-4210 1610);
FORCEPROP 2 LASTPIN (-4200 1550) $PN 4
J 2
(-4210 1560);
DISPLAY 0.617021 (-4210 1560);
PAINT ORANGE (-4210 1560);
FORCEPROP 2 LASTPIN (-3400 1600) $PN 3
J 0
(-3390 1610);
DISPLAY 0.617021 (-3390 1610);
PAINT ORANGE (-3390 1610);
FORCEPROP 2 LASTPIN (-3400 1500) $PN 1
J 0
(-3390 1510);
DISPLAY 0.617021 (-3390 1510);
PAINT ORANGE (-3390 1510);
FORCEPROP 2 LASTPIN (-3400 1450) $PN 2
J 0
(-3390 1460);
DISPLAY 0.617021 (-3390 1460);
PAINT ORANGE (-3390 1460);
FORCEPROP 1 LAST PACK_TYPE SOT
J 0
(-4150 1950);
PAINT SKYBLUE (-4150 1950);
DISPLAY INVISIBLE (-4150 1950);
FORCEPROP 2 LAST SEC_TYPE SOT
J 0
(-4150 1950);
DISPLAY 1.021277 (-4150 1950);
PAINT ORANGE (-4150 1950);
DISPLAY INVISIBLE (-4150 1950);
FORCEPROP 0 LAST BOM_COST PVDDQ_GHJ_VR
J 0
(-4150 2100);
DISPLAY 1.021277 (-4150 2100);
PAINT ORANGE (-4150 2100);
DISPLAY INVISIBLE (-4150 2100);
FORCEPROP 2 LAST CDS_LIB mstr_vreg
J 0
(-3800 1550);
PAINT ORANGE (-3800 1550);
DISPLAY INVISIBLE (-3800 1550);
FORCEPROP 2 LAST SEC 1
J 0
(-4150 1950);
DISPLAY 0.680851 (-4150 1950);
PAINT MONO (-4150 1950);
DISPLAY INVISIBLE (-4150 1950);
FORCEPROP 2 LAST CDS_LOCATION U1F1
J 0
(-4150 1900);
DISPLAY 0.617021 (-4150 1900);
PAINT AQUA (-4150 1900);
DISPLAY INVISIBLE (-4150 1900);
FORCEPROP 1 LAST PATH I133
J 0
(-3825 1850);
PAINT GREEN (-3825 1850);
DISPLAY INVISIBLE (-3825 1850);
FORCEPROP 2 LAST ROOM PVDDQ_GHJ_PWR_VR
J 0
(-4150 2000);
DISPLAY 1.021277 (-4150 2000);
PAINT ORANGE (-4150 2000);
DISPLAY INVISIBLE (-4150 2000);
FORCEADD OFFPAGE..5
R 2
(1950 4475);
FORCEPROP 2 LAST $XR0 226 
J 0
(2139 4475);
DISPLAY 0.638298 (2139 4475);
PAINT MONO (2139 4475);
FORCEPROP 2 LAST CDS_LIB mstr_standard
J 0
(1950 4475);
PAINT ORANGE (1950 4475);
DISPLAY INVISIBLE (1950 4475);
FORCEPROP 1 LAST OFFPAGE TRUE
J 2
(1625 4350);
DISPLAY 1.170213 (1625 4350);
PAINT GREEN (1625 4350);
DISPLAY INVISIBLE (1625 4350);
FORCEPROP 1 LAST COMMENT_BODY TRUE
J 2
(1850 4400);
DISPLAY 1.170213 (1850 4400);
PAINT GREEN (1850 4400);
DISPLAY INVISIBLE (1850 4400);
FORCEPROP 2 LAST PATH I134
J 0
(2125 4550);
DISPLAY 1.021277 (2125 4550);
PAINT ORANGE (2125 4550);
DISPLAY INVISIBLE (2125 4550);
FORCEADD RES..1
(1050 4475);
FORCEPROP 1 LAST LOCATION R1B14
J 0
(1000 4525);
DISPLAY 0.617021 (1000 4525);
PAINT AQUA (1000 4525);
FORCEPROP 1 LAST PART_NUMBER G21497-005
J 0
(1000 4575);
DISPLAY 0.617021 (1000 4575);
PAINT BLUE (1000 4575);
FORCEPROP 1 LAST VALUE 0.0
J 2
(950 4400);
DISPLAY 0.617021 (950 4400);
PAINT SKYBLUE (950 4400);
FORCEPROP 1 LAST TOLERANCE 5%
J 0
(1000 4400);
DISPLAY 0.617021 (1000 4400);
PAINT SKYBLUE (1000 4400);
FORCEPROP 1 LAST PACK_TYPE 0402
J 0
(850 4275);
DISPLAY 0.617021 (850 4275);
PAINT SKYBLUE (850 4275);
FORCEPROP 1 LAST MATERIAL CHIP
J 0
(950 4350);
DISPLAY 0.617021 (950 4350);
PAINT SKYBLUE (950 4350);
FORCEPROP 1 LAST WATTAGE 1/16W
J 2
(1250 4400);
DISPLAY 0.617021 (1250 4400);
PAINT SKYBLUE (1250 4400);
FORCEPROP 1 LASTPIN (1150 4475) $PN 2
J 0
(1112 4487);
DISPLAY 0.617021 (1112 4487);
PAINT ORANGE (1112 4487);
FORCEPROP 1 LASTPIN (950 4475) $PN 1
J 0
(962 4487);
DISPLAY 0.617021 (962 4487);
PAINT ORANGE (962 4487);
FORCEPROP 2 LAST SEC_TYPE 0402
J 0
(1000 4675);
DISPLAY 1.021277 (1000 4675);
PAINT ORANGE (1000 4675);
DISPLAY INVISIBLE (1000 4675);
FORCEPROP 2 LAST BOM_COST PVDDQ_KLM_VR
J 0
(1000 4725);
DISPLAY 1.361702 (1000 4725);
PAINT ORANGE (1000 4725);
DISPLAY INVISIBLE (1000 4725);
FORCEPROP 2 LAST CDS_LIB mstr_discrete
J 0
(1050 4475);
PAINT ORANGE (1050 4475);
DISPLAY INVISIBLE (1050 4475);
FORCEPROP 2 LAST SEC 1
J 0
(1000 4675);
DISPLAY 0.680851 (1000 4675);
PAINT MONO (1000 4675);
DISPLAY INVISIBLE (1000 4675);
FORCEPROP 2 LAST CDS_LOCATION R1B14
J 0
(1000 4525);
DISPLAY 0.617021 (1000 4525);
PAINT AQUA (1000 4525);
DISPLAY INVISIBLE (1000 4525);
FORCEPROP 1 LAST PATH I137
J 0
(1000 4625);
DISPLAY 0.978723 (1000 4625);
PAINT WHITE (1000 4625);
DISPLAY INVISIBLE (1000 4625);
FORCEPROP 2 LAST ROOM PVDDQ_KLM_PWR_VR
J 0
(1000 4625);
DISPLAY 1.361702 (1000 4625);
PAINT ORANGE (1000 4625);
DISPLAY INVISIBLE (1000 4625);
FORCEADD GND..1
(575 4150);
FORCEPROP 3 LASTPIN (575 4200) SIG_NAME GND\g
J 0
(585 4210);
DISPLAY 0.659574 (585 4210);
PAINT MONO (585 4210);
DISPLAY INVISIBLE (585 4210);
FORCEPROP 1 LAST VOLTAGE 0.0V
J 0
(530 4107);
DISPLAY 0.340426 (530 4107);
PAINT SKYBLUE (530 4107);
DISPLAY INVISIBLE (530 4107);
FORCEPROP 1 LAST SIZE 1B
J 0
(650 4100);
DISPLAY 1.170213 (650 4100);
PAINT AQUA (650 4100);
DISPLAY INVISIBLE (650 4100);
FORCEPROP 2 LAST CDS_LIB mstr_symbols
J 0
(575 4150);
PAINT ORANGE (575 4150);
DISPLAY INVISIBLE (575 4150);
FORCEPROP 1 LAST BODY_TYPE PLUMBING
J 0
(530 4107);
DISPLAY 0.340426 (530 4107);
PAINT GREEN (530 4107);
DISPLAY INVISIBLE (530 4107);
FORCEPROP 1 LAST PATH I140
J 0
(650 4150);
DISPLAY 0.872340 (650 4150);
PAINT AQUA (650 4150);
DISPLAY INVISIBLE (650 4150);
FORCEPROP 1 LAST HDL_POWER GND
J 0
(575 4300);
DISPLAY 1.170213 (575 4300);
PAINT GREEN (575 4300);
DISPLAY INVISIBLE (575 4300);
FORCEADD RES..1
(-750 4750);
FORCEPROP 1 LAST LOCATION R9M4
J 0
(-800 4800);
DISPLAY 0.617021 (-800 4800);
PAINT AQUA (-800 4800);
FORCEPROP 1 LAST PART_NUMBER G52199-004
J 0
(-800 4850);
DISPLAY 0.617021 (-800 4850);
PAINT BLUE (-800 4850);
FORCEPROP 1 LAST VALUE 0.002
J 2
(-775 4650);
DISPLAY 0.617021 (-775 4650);
PAINT SKYBLUE (-775 4650);
FORCEPROP 1 LAST TOLERANCE 1%
J 0
(-750 4650);
DISPLAY 0.617021 (-750 4650);
PAINT SKYBLUE (-750 4650);
FORCEPROP 1 LAST PACK_TYPE 1206
J 0
(-625 4600);
DISPLAY 0.617021 (-625 4600);
PAINT SKYBLUE (-625 4600);
FORCEPROP 1 LAST MATERIAL CHIP
J 0
(-750 4600);
DISPLAY 0.617021 (-750 4600);
PAINT SKYBLUE (-750 4600);
FORCEPROP 1 LAST WATTAGE 1W
J 2
(-775 4600);
DISPLAY 0.617021 (-775 4600);
PAINT SKYBLUE (-775 4600);
FORCEPROP 1 LASTPIN (-650 4750) $PN 2
J 0
(-688 4762);
DISPLAY 0.617021 (-688 4762);
PAINT ORANGE (-688 4762);
FORCEPROP 1 LASTPIN (-850 4750) $PN 1
J 0
(-838 4762);
DISPLAY 0.617021 (-838 4762);
PAINT ORANGE (-838 4762);
FORCEPROP 2 LAST SEC_TYPE 1206
J 0
(-800 4950);
DISPLAY 1.021277 (-800 4950);
PAINT ORANGE (-800 4950);
DISPLAY INVISIBLE (-800 4950);
FORCEPROP 2 LAST BOM_COST PVDDQ_KLM_VR
J 0
(-800 4950);
DISPLAY 1.361702 (-800 4950);
PAINT ORANGE (-800 4950);
DISPLAY INVISIBLE (-800 4950);
FORCEPROP 2 LAST CDS_LIB mstr_discrete
J 0
(-750 4750);
PAINT ORANGE (-750 4750);
DISPLAY INVISIBLE (-750 4750);
FORCEPROP 2 LAST SEC 1
J 0
(-800 4950);
DISPLAY 0.680851 (-800 4950);
PAINT MONO (-800 4950);
DISPLAY INVISIBLE (-800 4950);
FORCEPROP 2 LAST CDS_LOCATION R9M4
J 0
(-800 4800);
DISPLAY 0.617021 (-800 4800);
PAINT AQUA (-800 4800);
DISPLAY INVISIBLE (-800 4800);
FORCEPROP 1 LAST PATH I142
J 0
(-800 4900);
DISPLAY 0.978723 (-800 4900);
PAINT WHITE (-800 4900);
DISPLAY INVISIBLE (-800 4900);
FORCEPROP 2 LAST ROOM PVDDQ_KLM_PWR_VR
J 0
(-800 4850);
DISPLAY 1.361702 (-800 4850);
PAINT ORANGE (-800 4850);
DISPLAY INVISIBLE (-800 4850);
FORCEADD P12V_NVDIMM_KLM..1
(-1050 4925);
FORCEPROP 3 LASTPIN (-1050 4875) SIG_NAME P12V_NVDIMM_KLM\g
J 0
(-1040 4885);
DISPLAY 0.659574 (-1040 4885);
PAINT MONO (-1040 4885);
DISPLAY INVISIBLE (-1040 4885);
FORCEPROP 1 LAST VOLTAGE 12.0
J 0
(-1095 4882);
DISPLAY 0.340426 (-1095 4882);
PAINT SKYBLUE (-1095 4882);
DISPLAY INVISIBLE (-1095 4882);
FORCEPROP 2 LAST CDS_LIB mstr_symbols
J 0
(-1050 4925);
PAINT ORANGE (-1050 4925);
DISPLAY INVISIBLE (-1050 4925);
FORCEPROP 1 LAST BODY_TYPE PLUMBING
J 0
(-1095 4882);
DISPLAY 0.340426 (-1095 4882);
PAINT GREEN (-1095 4882);
DISPLAY INVISIBLE (-1095 4882);
FORCEPROP 1 LAST PATH I143
J 0
(-1000 4950);
DISPLAY 0.872340 (-1000 4950);
PAINT AQUA (-1000 4950);
DISPLAY INVISIBLE (-1000 4950);
FORCEPROP 1 LAST HDL_POWER P12V_NVDIMM_KLM
J 1
(-1050 4975);
DISPLAY 0.872340 (-1050 4975);
PAINT GREEN (-1050 4975);
DISPLAY INVISIBLE (-1050 4975);
FORCEADD MAX9634..1
(25 4425);
FORCEPROP 1 LAST LOCATION U1B1
J 0
(-325 4775);
DISPLAY 0.617021 (-325 4775);
PAINT AQUA (-325 4775);
FORCEPROP 1 LAST PART_NUMBER H35789-001
J 0
(-325 4125);
DISPLAY 0.617021 (-325 4125);
PAINT BLUE (-325 4125);
FORCEPROP 1 LAST MATERIAL IC
J 0
(-325 4725);
DISPLAY 0.617021 (-325 4725);
PAINT SKYBLUE (-325 4725);
FORCEPROP 2 LASTPIN (-375 4475) $PN 5
J 2
(-385 4485);
DISPLAY 0.617021 (-385 4485);
PAINT ORANGE (-385 4485);
FORCEPROP 2 LASTPIN (-375 4425) $PN 4
J 2
(-385 4435);
DISPLAY 0.617021 (-385 4435);
PAINT ORANGE (-385 4435);
FORCEPROP 2 LASTPIN (425 4475) $PN 3
J 0
(435 4485);
DISPLAY 0.617021 (435 4485);
PAINT ORANGE (435 4485);
FORCEPROP 2 LASTPIN (425 4375) $PN 1
J 0
(435 4385);
DISPLAY 0.617021 (435 4385);
PAINT ORANGE (435 4385);
FORCEPROP 2 LASTPIN (425 4325) $PN 2
J 0
(435 4335);
DISPLAY 0.617021 (435 4335);
PAINT ORANGE (435 4335);
FORCEPROP 1 LAST PACK_TYPE SOT
J 0
(-325 4825);
PAINT SKYBLUE (-325 4825);
DISPLAY INVISIBLE (-325 4825);
FORCEPROP 2 LAST SEC_TYPE SOT
J 0
(-325 4825);
DISPLAY 1.021277 (-325 4825);
PAINT ORANGE (-325 4825);
DISPLAY INVISIBLE (-325 4825);
FORCEPROP 0 LAST BOM_COST PVDDQ_KLM_VR
J 0
(-325 4975);
DISPLAY 1.021277 (-325 4975);
PAINT ORANGE (-325 4975);
DISPLAY INVISIBLE (-325 4975);
FORCEPROP 2 LAST CDS_LIB mstr_vreg
J 0
(25 4425);
PAINT ORANGE (25 4425);
DISPLAY INVISIBLE (25 4425);
FORCEPROP 2 LAST SEC 1
J 0
(-325 4825);
DISPLAY 0.680851 (-325 4825);
PAINT MONO (-325 4825);
DISPLAY INVISIBLE (-325 4825);
FORCEPROP 2 LAST CDS_LOCATION U1B1
J 0
(-325 4775);
DISPLAY 0.617021 (-325 4775);
PAINT AQUA (-325 4775);
DISPLAY INVISIBLE (-325 4775);
FORCEPROP 1 LAST PATH I144
J 0
(0 4725);
PAINT GREEN (0 4725);
DISPLAY INVISIBLE (0 4725);
FORCEPROP 2 LAST ROOM PVDDQ_KLM_PWR_VR
J 0
(-325 4875);
DISPLAY 1.021277 (-325 4875);
PAINT ORANGE (-325 4875);
DISPLAY INVISIBLE (-325 4875);
FORCEADD P12V_STBY..1
(-4200 4925);
FORCEPROP 3 LASTPIN (-4200 4875) SIG_NAME P12V_STBY\g
J 0
(-4190 4885);
DISPLAY 0.659574 (-4190 4885);
PAINT MONO (-4190 4885);
DISPLAY INVISIBLE (-4190 4885);
FORCEPROP 1 LAST VOLTAGE 12.0V
J 0
(-4245 4882);
DISPLAY 0.340426 (-4245 4882);
PAINT SKYBLUE (-4245 4882);
DISPLAY INVISIBLE (-4245 4882);
FORCEPROP 1 LAST SIZE 1B
J 0
(-4155 4947);
DISPLAY 0.340426 (-4155 4947);
PAINT GREEN (-4155 4947);
DISPLAY INVISIBLE (-4155 4947);
FORCEPROP 2 LAST CDS_LIB mstr_symbols
J 0
(-4200 4925);
PAINT ORANGE (-4200 4925);
DISPLAY INVISIBLE (-4200 4925);
FORCEPROP 1 LAST BODY_TYPE PLUMBING
J 0
(-4245 4882);
DISPLAY 0.340426 (-4245 4882);
PAINT GREEN (-4245 4882);
DISPLAY INVISIBLE (-4245 4882);
FORCEPROP 1 LAST PATH I145
J 0
(-4155 4927);
DISPLAY 0.340426 (-4155 4927);
PAINT GREEN (-4155 4927);
DISPLAY INVISIBLE (-4155 4927);
FORCEPROP 1 LAST HDL_POWER P12V_STBY
J 0
(-4500 4800);
DISPLAY 0.872340 (-4500 4800);
PAINT ORANGE (-4500 4800);
DISPLAY INVISIBLE (-4500 4800);
FORCEADD P12V_STBY..1
(-4200 3475);
FORCEPROP 3 LASTPIN (-4200 3425) SIG_NAME P12V_STBY\g
J 0
(-4190 3435);
DISPLAY 0.659574 (-4190 3435);
PAINT MONO (-4190 3435);
DISPLAY INVISIBLE (-4190 3435);
FORCEPROP 1 LAST VOLTAGE 12.0V
J 0
(-4245 3432);
DISPLAY 0.340426 (-4245 3432);
PAINT SKYBLUE (-4245 3432);
DISPLAY INVISIBLE (-4245 3432);
FORCEPROP 1 LAST SIZE 1B
J 0
(-4155 3497);
DISPLAY 0.340426 (-4155 3497);
PAINT GREEN (-4155 3497);
DISPLAY INVISIBLE (-4155 3497);
FORCEPROP 2 LAST CDS_LIB mstr_symbols
J 0
(-4200 3475);
PAINT ORANGE (-4200 3475);
DISPLAY INVISIBLE (-4200 3475);
FORCEPROP 1 LAST BODY_TYPE PLUMBING
J 0
(-4245 3432);
DISPLAY 0.340426 (-4245 3432);
PAINT GREEN (-4245 3432);
DISPLAY INVISIBLE (-4245 3432);
FORCEPROP 1 LAST PATH I146
J 0
(-4155 3477);
DISPLAY 0.340426 (-4155 3477);
PAINT GREEN (-4155 3477);
DISPLAY INVISIBLE (-4155 3477);
FORCEPROP 1 LAST HDL_POWER P12V_STBY
J 0
(-4500 3350);
DISPLAY 0.872340 (-4500 3350);
PAINT ORANGE (-4500 3350);
DISPLAY INVISIBLE (-4500 3350);
FORCEADD P12V_STBY..1
(-375 4925);
FORCEPROP 3 LASTPIN (-375 4875) SIG_NAME P12V_STBY\g
J 0
(-365 4885);
DISPLAY 0.659574 (-365 4885);
PAINT MONO (-365 4885);
DISPLAY INVISIBLE (-365 4885);
FORCEPROP 1 LAST VOLTAGE 12.0V
J 0
(-420 4882);
DISPLAY 0.340426 (-420 4882);
PAINT SKYBLUE (-420 4882);
DISPLAY INVISIBLE (-420 4882);
FORCEPROP 1 LAST SIZE 1B
J 0
(-330 4947);
DISPLAY 0.340426 (-330 4947);
PAINT GREEN (-330 4947);
DISPLAY INVISIBLE (-330 4947);
FORCEPROP 2 LAST CDS_LIB mstr_symbols
J 0
(-375 4925);
PAINT ORANGE (-375 4925);
DISPLAY INVISIBLE (-375 4925);
FORCEPROP 1 LAST BODY_TYPE PLUMBING
J 0
(-420 4882);
DISPLAY 0.340426 (-420 4882);
PAINT GREEN (-420 4882);
DISPLAY INVISIBLE (-420 4882);
FORCEPROP 1 LAST PATH I147
J 0
(-330 4927);
DISPLAY 0.340426 (-330 4927);
PAINT GREEN (-330 4927);
DISPLAY INVISIBLE (-330 4927);
FORCEPROP 1 LAST HDL_POWER P12V_STBY
J 0
(-675 4800);
DISPLAY 0.872340 (-675 4800);
PAINT ORANGE (-675 4800);
DISPLAY INVISIBLE (-675 4800);
FORCEADD P12V_STBY..1
(-4200 2050);
FORCEPROP 3 LASTPIN (-4200 2000) SIG_NAME P12V_STBY\g
J 0
(-4190 2010);
DISPLAY 0.659574 (-4190 2010);
PAINT MONO (-4190 2010);
DISPLAY INVISIBLE (-4190 2010);
FORCEPROP 1 LAST VOLTAGE 12.0V
J 0
(-4245 2007);
DISPLAY 0.340426 (-4245 2007);
PAINT SKYBLUE (-4245 2007);
DISPLAY INVISIBLE (-4245 2007);
FORCEPROP 1 LAST SIZE 1B
J 0
(-4155 2072);
DISPLAY 0.340426 (-4155 2072);
PAINT GREEN (-4155 2072);
DISPLAY INVISIBLE (-4155 2072);
FORCEPROP 2 LAST CDS_LIB mstr_symbols
J 0
(-4200 2050);
PAINT ORANGE (-4200 2050);
DISPLAY INVISIBLE (-4200 2050);
FORCEPROP 1 LAST BODY_TYPE PLUMBING
J 0
(-4245 2007);
DISPLAY 0.340426 (-4245 2007);
PAINT GREEN (-4245 2007);
DISPLAY INVISIBLE (-4245 2007);
FORCEPROP 1 LAST PATH I148
J 0
(-4155 2052);
DISPLAY 0.340426 (-4155 2052);
PAINT GREEN (-4155 2052);
DISPLAY INVISIBLE (-4155 2052);
FORCEPROP 1 LAST HDL_POWER P12V_STBY
J 0
(-4500 1925);
DISPLAY 0.872340 (-4500 1925);
PAINT ORANGE (-4500 1925);
DISPLAY INVISIBLE (-4500 1925);
FORCEADD GND..1
(-825 1425);
FORCEPROP 3 LASTPIN (-825 1475) SIG_NAME GND\g
J 0
(-815 1485);
DISPLAY 0.659574 (-815 1485);
PAINT MONO (-815 1485);
DISPLAY INVISIBLE (-815 1485);
FORCEPROP 1 LAST VOLTAGE 0.0V
J 0
(-870 1382);
DISPLAY 0.340426 (-870 1382);
PAINT SKYBLUE (-870 1382);
DISPLAY INVISIBLE (-870 1382);
FORCEPROP 1 LAST SIZE 1B
J 0
(-750 1375);
DISPLAY 1.170213 (-750 1375);
PAINT AQUA (-750 1375);
DISPLAY INVISIBLE (-750 1375);
FORCEPROP 2 LAST CDS_LIB mstr_symbols
J 0
(-825 1425);
PAINT ORANGE (-825 1425);
DISPLAY INVISIBLE (-825 1425);
FORCEPROP 1 LAST BODY_TYPE PLUMBING
J 0
(-870 1382);
DISPLAY 0.340426 (-870 1382);
PAINT GREEN (-870 1382);
DISPLAY INVISIBLE (-870 1382);
FORCEPROP 1 LAST PATH I51
J 0
(-750 1425);
DISPLAY 0.872340 (-750 1425);
PAINT AQUA (-750 1425);
DISPLAY INVISIBLE (-750 1425);
FORCEPROP 1 LAST HDL_POWER GND
J 0
(-825 1575);
DISPLAY 1.170213 (-825 1575);
PAINT GREEN (-825 1575);
DISPLAY INVISIBLE (-825 1575);
FORCEADD CAP..1
(-825 1625);
FORCEPROP 1 LAST LOCATION C6U18
J 0
(-775 1725);
DISPLAY 0.617021 (-775 1725);
PAINT AQUA (-775 1725);
FORCEPROP 1 LAST PART_NUMBER G10601-001
J 0
(-775 1475);
DISPLAY 0.617021 (-775 1475);
PAINT BLUE (-775 1475);
FORCEPROP 1 LAST VALUE 10UF
J 0
(-775 1675);
DISPLAY 0.617021 (-775 1675);
PAINT SKYBLUE (-775 1675);
FORCEPROP 1 LAST TOLERANCE 10%
J 0
(-775 1575);
DISPLAY 0.617021 (-775 1575);
PAINT SKYBLUE (-775 1575);
FORCEPROP 1 LAST PACK_TYPE 0805
J 0
(-775 1425);
DISPLAY 0.617021 (-775 1425);
PAINT SKYBLUE (-775 1425);
FORCEPROP 1 LAST VOLTAGE 16V
J 0
(-775 1625);
DISPLAY 0.617021 (-775 1625);
PAINT SKYBLUE (-775 1625);
FORCEPROP 1 LAST MATERIAL X7R
J 0
(-775 1525);
DISPLAY 0.617021 (-775 1525);
PAINT SKYBLUE (-775 1525);
FORCEPROP 1 LASTPIN (-825 1525) $PN 2
J 0
(-815 1505);
DISPLAY 0.617021 (-815 1505);
PAINT WHITE (-815 1505);
FORCEPROP 1 LASTPIN (-825 1725) $PN 1
J 0
(-815 1705);
DISPLAY 0.617021 (-815 1705);
PAINT WHITE (-815 1705);
FORCEPROP 2 LAST CDS_LIB mstr_discrete
J 0
(-825 1625);
PAINT ORANGE (-825 1625);
DISPLAY INVISIBLE (-825 1625);
FORCEPROP 2 LAST CDS_SEC 1
J 0
(-775 1825);
DISPLAY 1.361702 (-775 1825);
PAINT ORANGE (-775 1825);
DISPLAY INVISIBLE (-775 1825);
FORCEPROP 2 LAST $SEC 1
J 0
(-775 1825);
DISPLAY 0.914894 (-775 1825);
PAINT MONO (-775 1825);
DISPLAY INVISIBLE (-775 1825);
FORCEPROP 2 LAST CDS_LOCATION C6U18
J 0
(-775 1725);
DISPLAY 0.617021 (-775 1725);
PAINT AQUA (-775 1725);
DISPLAY INVISIBLE (-775 1725);
FORCEPROP 1 LAST PATH I52
J 0
(-775 1775);
DISPLAY 0.978723 (-775 1775);
PAINT WHITE (-775 1775);
DISPLAY INVISIBLE (-775 1775);
FORCEPROP 0 LAST ROOM PVDDQ_ABC_PWR_VR
J 0
(-775 1775);
DISPLAY 1.021277 (-775 1775);
PAINT ORANGE (-775 1775);
DISPLAY INVISIBLE (-775 1775);
FORCEADD P12V_NVDIMM_ABC..1
(-825 1800);
FORCEPROP 3 LASTPIN (-825 1750) SIG_NAME P12V_NVDIMM_ABC\g
J 0
(-815 1760);
DISPLAY 0.659574 (-815 1760);
PAINT MONO (-815 1760);
DISPLAY INVISIBLE (-815 1760);
FORCEPROP 1 LAST VOLTAGE 12.0
J 0
(-870 1757);
DISPLAY 0.340426 (-870 1757);
PAINT SKYBLUE (-870 1757);
DISPLAY INVISIBLE (-870 1757);
FORCEPROP 2 LAST CDS_LIB mstr_symbols
J 0
(-825 1800);
PAINT ORANGE (-825 1800);
DISPLAY INVISIBLE (-825 1800);
FORCEPROP 1 LAST BODY_TYPE PLUMBING
J 0
(-870 1757);
DISPLAY 0.340426 (-870 1757);
PAINT GREEN (-870 1757);
DISPLAY INVISIBLE (-870 1757);
FORCEPROP 1 LAST PATH I53
J 0
(-775 1825);
DISPLAY 0.872340 (-775 1825);
PAINT AQUA (-775 1825);
DISPLAY INVISIBLE (-775 1825);
FORCEPROP 1 LAST HDL_POWER P12V_NVDIMM_ABC
J 1
(-825 1825);
DISPLAY 0.872340 (-825 1825);
PAINT GREEN (-825 1825);
DISPLAY INVISIBLE (-825 1825);
FORCEADD CAP..1
(-825 2200);
FORCEPROP 1 LAST LOCATION C6T2
J 0
(-775 2300);
DISPLAY 0.617021 (-775 2300);
PAINT AQUA (-775 2300);
FORCEPROP 1 LAST PART_NUMBER G10601-001
J 0
(-775 2050);
DISPLAY 0.617021 (-775 2050);
PAINT BLUE (-775 2050);
FORCEPROP 1 LAST VALUE 10UF
J 0
(-775 2250);
DISPLAY 0.617021 (-775 2250);
PAINT SKYBLUE (-775 2250);
FORCEPROP 1 LAST TOLERANCE 10%
J 0
(-775 2150);
DISPLAY 0.617021 (-775 2150);
PAINT SKYBLUE (-775 2150);
FORCEPROP 1 LAST PACK_TYPE 0805
J 0
(-775 2000);
DISPLAY 0.617021 (-775 2000);
PAINT SKYBLUE (-775 2000);
FORCEPROP 1 LAST VOLTAGE 16V
J 0
(-775 2200);
DISPLAY 0.617021 (-775 2200);
PAINT SKYBLUE (-775 2200);
FORCEPROP 1 LAST MATERIAL X7R
J 0
(-775 2100);
DISPLAY 0.617021 (-775 2100);
PAINT SKYBLUE (-775 2100);
FORCEPROP 1 LASTPIN (-825 2100) $PN 2
J 0
(-815 2080);
DISPLAY 0.617021 (-815 2080);
PAINT WHITE (-815 2080);
FORCEPROP 1 LASTPIN (-825 2300) $PN 1
J 0
(-815 2280);
DISPLAY 0.617021 (-815 2280);
PAINT WHITE (-815 2280);
FORCEPROP 2 LAST CDS_LIB mstr_discrete
J 0
(-825 2200);
PAINT ORANGE (-825 2200);
DISPLAY INVISIBLE (-825 2200);
FORCEPROP 2 LAST CDS_SEC 1
J 0
(-775 2400);
DISPLAY 1.361702 (-775 2400);
PAINT ORANGE (-775 2400);
DISPLAY INVISIBLE (-775 2400);
FORCEPROP 2 LAST $SEC 1
J 0
(-775 2400);
DISPLAY 0.914894 (-775 2400);
PAINT MONO (-775 2400);
DISPLAY INVISIBLE (-775 2400);
FORCEPROP 2 LAST CDS_LOCATION C6T2
J 0
(-775 2300);
DISPLAY 0.617021 (-775 2300);
PAINT AQUA (-775 2300);
DISPLAY INVISIBLE (-775 2300);
FORCEPROP 1 LAST PATH I54
J 0
(-775 2350);
DISPLAY 0.978723 (-775 2350);
PAINT WHITE (-775 2350);
DISPLAY INVISIBLE (-775 2350);
FORCEPROP 0 LAST ROOM PVDDQ_ABC_PWR_VR
J 0
(-775 2350);
DISPLAY 1.021277 (-775 2350);
PAINT ORANGE (-775 2350);
DISPLAY INVISIBLE (-775 2350);
FORCEADD GND..1
(-825 2000);
FORCEPROP 3 LASTPIN (-825 2050) SIG_NAME GND\g
J 0
(-815 2060);
DISPLAY 0.659574 (-815 2060);
PAINT MONO (-815 2060);
DISPLAY INVISIBLE (-815 2060);
FORCEPROP 1 LAST VOLTAGE 0.0V
J 0
(-870 1957);
DISPLAY 0.340426 (-870 1957);
PAINT SKYBLUE (-870 1957);
DISPLAY INVISIBLE (-870 1957);
FORCEPROP 1 LAST SIZE 1B
J 0
(-750 1950);
DISPLAY 1.170213 (-750 1950);
PAINT AQUA (-750 1950);
DISPLAY INVISIBLE (-750 1950);
FORCEPROP 2 LAST CDS_LIB mstr_symbols
J 0
(-825 2000);
PAINT ORANGE (-825 2000);
DISPLAY INVISIBLE (-825 2000);
FORCEPROP 1 LAST BODY_TYPE PLUMBING
J 0
(-870 1957);
DISPLAY 0.340426 (-870 1957);
PAINT GREEN (-870 1957);
DISPLAY INVISIBLE (-870 1957);
FORCEPROP 1 LAST PATH I55
J 0
(-750 2000);
DISPLAY 0.872340 (-750 2000);
PAINT AQUA (-750 2000);
DISPLAY INVISIBLE (-750 2000);
FORCEPROP 1 LAST HDL_POWER GND
J 0
(-825 2150);
DISPLAY 1.170213 (-825 2150);
PAINT GREEN (-825 2150);
DISPLAY INVISIBLE (-825 2150);
FORCEADD P12V_NVDIMM_ABC..1
(-825 2375);
FORCEPROP 3 LASTPIN (-825 2325) SIG_NAME P12V_NVDIMM_ABC\g
J 0
(-815 2335);
DISPLAY 0.659574 (-815 2335);
PAINT MONO (-815 2335);
DISPLAY INVISIBLE (-815 2335);
FORCEPROP 1 LAST VOLTAGE 12.0
J 0
(-870 2332);
DISPLAY 0.340426 (-870 2332);
PAINT SKYBLUE (-870 2332);
DISPLAY INVISIBLE (-870 2332);
FORCEPROP 2 LAST CDS_LIB mstr_symbols
J 0
(-825 2375);
PAINT ORANGE (-825 2375);
DISPLAY INVISIBLE (-825 2375);
FORCEPROP 1 LAST BODY_TYPE PLUMBING
J 0
(-870 2332);
DISPLAY 0.340426 (-870 2332);
PAINT GREEN (-870 2332);
DISPLAY INVISIBLE (-870 2332);
FORCEPROP 1 LAST PATH I56
J 0
(-775 2400);
DISPLAY 0.872340 (-775 2400);
PAINT AQUA (-775 2400);
DISPLAY INVISIBLE (-775 2400);
FORCEPROP 1 LAST HDL_POWER P12V_NVDIMM_ABC
J 1
(-825 2400);
DISPLAY 0.872340 (-825 2400);
PAINT GREEN (-825 2400);
DISPLAY INVISIBLE (-825 2400);
FORCEADD GND..1
(-825 2650);
FORCEPROP 3 LASTPIN (-825 2700) SIG_NAME GND\g
J 0
(-815 2710);
DISPLAY 0.659574 (-815 2710);
PAINT MONO (-815 2710);
DISPLAY INVISIBLE (-815 2710);
FORCEPROP 1 LAST VOLTAGE 0.0V
J 0
(-870 2607);
DISPLAY 0.340426 (-870 2607);
PAINT SKYBLUE (-870 2607);
DISPLAY INVISIBLE (-870 2607);
FORCEPROP 1 LAST SIZE 1B
J 0
(-750 2600);
DISPLAY 1.170213 (-750 2600);
PAINT AQUA (-750 2600);
DISPLAY INVISIBLE (-750 2600);
FORCEPROP 2 LAST CDS_LIB mstr_symbols
J 0
(-825 2650);
PAINT ORANGE (-825 2650);
DISPLAY INVISIBLE (-825 2650);
FORCEPROP 1 LAST BODY_TYPE PLUMBING
J 0
(-870 2607);
DISPLAY 0.340426 (-870 2607);
PAINT GREEN (-870 2607);
DISPLAY INVISIBLE (-870 2607);
FORCEPROP 1 LAST PATH I57
J 0
(-750 2650);
DISPLAY 0.872340 (-750 2650);
PAINT AQUA (-750 2650);
DISPLAY INVISIBLE (-750 2650);
FORCEPROP 1 LAST HDL_POWER GND
J 0
(-825 2800);
DISPLAY 1.170213 (-825 2800);
PAINT GREEN (-825 2800);
DISPLAY INVISIBLE (-825 2800);
FORCEADD GND..1
(25 1425);
FORCEPROP 3 LASTPIN (25 1475) SIG_NAME GND\g
J 0
(35 1485);
DISPLAY 0.659574 (35 1485);
PAINT MONO (35 1485);
DISPLAY INVISIBLE (35 1485);
FORCEPROP 1 LAST VOLTAGE 0.0V
J 0
(-20 1382);
DISPLAY 0.340426 (-20 1382);
PAINT SKYBLUE (-20 1382);
DISPLAY INVISIBLE (-20 1382);
FORCEPROP 2 LAST CDS_LIB mstr_symbols
J 0
(25 1425);
PAINT ORANGE (25 1425);
DISPLAY INVISIBLE (25 1425);
FORCEPROP 1 LAST SIZE 1B
J 0
(100 1375);
DISPLAY 1.170213 (100 1375);
PAINT AQUA (100 1375);
DISPLAY INVISIBLE (100 1375);
FORCEPROP 1 LAST BODY_TYPE PLUMBING
J 0
(-20 1382);
DISPLAY 0.340426 (-20 1382);
PAINT GREEN (-20 1382);
DISPLAY INVISIBLE (-20 1382);
FORCEPROP 1 LAST PATH I58
J 0
(100 1425);
DISPLAY 0.872340 (100 1425);
PAINT AQUA (100 1425);
DISPLAY INVISIBLE (100 1425);
FORCEPROP 1 LAST HDL_POWER GND
J 0
(25 1575);
DISPLAY 1.170213 (25 1575);
PAINT GREEN (25 1575);
DISPLAY INVISIBLE (25 1575);
FORCEADD CAP..1
(25 1625);
FORCEPROP 1 LAST LOCATION C4B11
J 0
(75 1725);
DISPLAY 0.617021 (75 1725);
PAINT AQUA (75 1725);
FORCEPROP 1 LAST PART_NUMBER G10601-001
J 0
(75 1475);
DISPLAY 0.617021 (75 1475);
PAINT BLUE (75 1475);
FORCEPROP 1 LAST VALUE 10UF
J 0
(75 1675);
DISPLAY 0.617021 (75 1675);
PAINT SKYBLUE (75 1675);
FORCEPROP 1 LAST TOLERANCE 10%
J 0
(75 1575);
DISPLAY 0.617021 (75 1575);
PAINT SKYBLUE (75 1575);
FORCEPROP 1 LAST PACK_TYPE 0805
J 0
(75 1425);
DISPLAY 0.617021 (75 1425);
PAINT SKYBLUE (75 1425);
FORCEPROP 1 LAST VOLTAGE 16V
J 0
(75 1625);
DISPLAY 0.617021 (75 1625);
PAINT SKYBLUE (75 1625);
FORCEPROP 1 LAST MATERIAL X7R
J 0
(75 1525);
DISPLAY 0.617021 (75 1525);
PAINT SKYBLUE (75 1525);
FORCEPROP 1 LASTPIN (25 1525) $PN 2
J 0
(35 1505);
DISPLAY 0.617021 (35 1505);
PAINT WHITE (35 1505);
FORCEPROP 1 LASTPIN (25 1725) $PN 1
J 0
(35 1705);
DISPLAY 0.617021 (35 1705);
PAINT WHITE (35 1705);
FORCEPROP 2 LAST CDS_LIB mstr_discrete
J 0
(25 1625);
PAINT ORANGE (25 1625);
DISPLAY INVISIBLE (25 1625);
FORCEPROP 2 LAST CDS_SEC 1
J 0
(75 1825);
DISPLAY 1.361702 (75 1825);
PAINT ORANGE (75 1825);
DISPLAY INVISIBLE (75 1825);
FORCEPROP 2 LAST $SEC 1
J 0
(75 1825);
DISPLAY 0.914894 (75 1825);
PAINT MONO (75 1825);
DISPLAY INVISIBLE (75 1825);
FORCEPROP 2 LAST CDS_LOCATION C4B11
J 0
(75 1725);
DISPLAY 0.617021 (75 1725);
PAINT AQUA (75 1725);
DISPLAY INVISIBLE (75 1725);
FORCEPROP 1 LAST PATH I59
J 0
(75 1775);
DISPLAY 0.978723 (75 1775);
PAINT WHITE (75 1775);
DISPLAY INVISIBLE (75 1775);
FORCEPROP 0 LAST ROOM PVDDQ_DEF_PWR_VR
J 0
(75 1775);
DISPLAY 1.021277 (75 1775);
PAINT ORANGE (75 1775);
DISPLAY INVISIBLE (75 1775);
FORCEADD P12V_NVDIMM_DEF..1
(25 1800);
FORCEPROP 3 LASTPIN (25 1750) SIG_NAME P12V_NVDIMM_DEF\g
J 0
(35 1760);
DISPLAY 0.659574 (35 1760);
PAINT MONO (35 1760);
DISPLAY INVISIBLE (35 1760);
FORCEPROP 1 LAST VOLTAGE 12.0
J 0
(-20 1757);
DISPLAY 0.340426 (-20 1757);
PAINT SKYBLUE (-20 1757);
DISPLAY INVISIBLE (-20 1757);
FORCEPROP 2 LAST CDS_LIB mstr_symbols
J 0
(25 1800);
PAINT ORANGE (25 1800);
DISPLAY INVISIBLE (25 1800);
FORCEPROP 1 LAST BODY_TYPE PLUMBING
J 0
(-20 1757);
DISPLAY 0.340426 (-20 1757);
PAINT GREEN (-20 1757);
DISPLAY INVISIBLE (-20 1757);
FORCEPROP 1 LAST PATH I60
J 0
(75 1825);
DISPLAY 0.872340 (75 1825);
PAINT AQUA (75 1825);
DISPLAY INVISIBLE (75 1825);
FORCEPROP 1 LAST HDL_POWER P12V_NVDIMM_DEF
J 1
(25 1850);
DISPLAY 0.872340 (25 1850);
PAINT GREEN (25 1850);
DISPLAY INVISIBLE (25 1850);
FORCEADD GND..1
(25 2000);
FORCEPROP 3 LASTPIN (25 2050) SIG_NAME GND\g
J 0
(35 2060);
DISPLAY 0.659574 (35 2060);
PAINT MONO (35 2060);
DISPLAY INVISIBLE (35 2060);
FORCEPROP 1 LAST VOLTAGE 0.0V
J 0
(-20 1957);
DISPLAY 0.340426 (-20 1957);
PAINT SKYBLUE (-20 1957);
DISPLAY INVISIBLE (-20 1957);
FORCEPROP 2 LAST CDS_LIB mstr_symbols
J 0
(25 2000);
PAINT ORANGE (25 2000);
DISPLAY INVISIBLE (25 2000);
FORCEPROP 1 LAST SIZE 1B
J 0
(100 1950);
DISPLAY 1.170213 (100 1950);
PAINT AQUA (100 1950);
DISPLAY INVISIBLE (100 1950);
FORCEPROP 1 LAST BODY_TYPE PLUMBING
J 0
(-20 1957);
DISPLAY 0.340426 (-20 1957);
PAINT GREEN (-20 1957);
DISPLAY INVISIBLE (-20 1957);
FORCEPROP 1 LAST PATH I61
J 0
(100 2000);
DISPLAY 0.872340 (100 2000);
PAINT AQUA (100 2000);
DISPLAY INVISIBLE (100 2000);
FORCEPROP 1 LAST HDL_POWER GND
J 0
(25 2150);
DISPLAY 1.170213 (25 2150);
PAINT GREEN (25 2150);
DISPLAY INVISIBLE (25 2150);
FORCEADD CAP..1
(25 2200);
FORCEPROP 1 LAST LOCATION C4A4
J 0
(75 2300);
DISPLAY 0.617021 (75 2300);
PAINT AQUA (75 2300);
FORCEPROP 1 LAST PART_NUMBER G10601-001
J 0
(75 2050);
DISPLAY 0.617021 (75 2050);
PAINT BLUE (75 2050);
FORCEPROP 1 LAST VALUE 10UF
J 0
(75 2250);
DISPLAY 0.617021 (75 2250);
PAINT SKYBLUE (75 2250);
FORCEPROP 1 LAST TOLERANCE 10%
J 0
(75 2150);
DISPLAY 0.617021 (75 2150);
PAINT SKYBLUE (75 2150);
FORCEPROP 1 LAST PACK_TYPE 0805
J 0
(75 2000);
DISPLAY 0.617021 (75 2000);
PAINT SKYBLUE (75 2000);
FORCEPROP 1 LAST VOLTAGE 16V
J 0
(75 2200);
DISPLAY 0.617021 (75 2200);
PAINT SKYBLUE (75 2200);
FORCEPROP 1 LAST MATERIAL X7R
J 0
(75 2100);
DISPLAY 0.617021 (75 2100);
PAINT SKYBLUE (75 2100);
FORCEPROP 1 LASTPIN (25 2100) $PN 2
J 0
(35 2080);
DISPLAY 0.617021 (35 2080);
PAINT WHITE (35 2080);
FORCEPROP 1 LASTPIN (25 2300) $PN 1
J 0
(35 2280);
DISPLAY 0.617021 (35 2280);
PAINT WHITE (35 2280);
FORCEPROP 2 LAST CDS_LIB mstr_discrete
J 0
(25 2200);
PAINT ORANGE (25 2200);
DISPLAY INVISIBLE (25 2200);
FORCEPROP 2 LAST CDS_SEC 1
J 0
(75 2400);
DISPLAY 1.361702 (75 2400);
PAINT ORANGE (75 2400);
DISPLAY INVISIBLE (75 2400);
FORCEPROP 2 LAST $SEC 1
J 0
(75 2400);
DISPLAY 0.914894 (75 2400);
PAINT MONO (75 2400);
DISPLAY INVISIBLE (75 2400);
FORCEPROP 2 LAST CDS_LOCATION C4A4
J 0
(75 2300);
DISPLAY 0.617021 (75 2300);
PAINT AQUA (75 2300);
DISPLAY INVISIBLE (75 2300);
FORCEPROP 1 LAST PATH I62
J 0
(75 2350);
DISPLAY 0.978723 (75 2350);
PAINT WHITE (75 2350);
DISPLAY INVISIBLE (75 2350);
FORCEPROP 0 LAST ROOM PVDDQ_DEF_PWR_VR
J 0
(75 2350);
DISPLAY 1.021277 (75 2350);
PAINT ORANGE (75 2350);
DISPLAY INVISIBLE (75 2350);
FORCEADD P12V_NVDIMM_DEF..1
(25 2375);
FORCEPROP 3 LASTPIN (25 2325) SIG_NAME P12V_NVDIMM_DEF\g
J 0
(35 2335);
DISPLAY 0.659574 (35 2335);
PAINT MONO (35 2335);
DISPLAY INVISIBLE (35 2335);
FORCEPROP 1 LAST VOLTAGE 12.0
J 0
(-20 2332);
DISPLAY 0.340426 (-20 2332);
PAINT SKYBLUE (-20 2332);
DISPLAY INVISIBLE (-20 2332);
FORCEPROP 2 LAST CDS_LIB mstr_symbols
J 0
(25 2375);
PAINT ORANGE (25 2375);
DISPLAY INVISIBLE (25 2375);
FORCEPROP 1 LAST BODY_TYPE PLUMBING
J 0
(-20 2332);
DISPLAY 0.340426 (-20 2332);
PAINT GREEN (-20 2332);
DISPLAY INVISIBLE (-20 2332);
FORCEPROP 1 LAST PATH I63
J 0
(75 2400);
DISPLAY 0.872340 (75 2400);
PAINT AQUA (75 2400);
DISPLAY INVISIBLE (75 2400);
FORCEPROP 1 LAST HDL_POWER P12V_NVDIMM_DEF
J 1
(25 2425);
DISPLAY 0.872340 (25 2425);
PAINT GREEN (25 2425);
DISPLAY INVISIBLE (25 2425);
FORCEADD GND..1
(25 2650);
FORCEPROP 3 LASTPIN (25 2700) SIG_NAME GND\g
J 0
(35 2710);
DISPLAY 0.659574 (35 2710);
PAINT MONO (35 2710);
DISPLAY INVISIBLE (35 2710);
FORCEPROP 1 LAST VOLTAGE 0.0V
J 0
(-20 2607);
DISPLAY 0.340426 (-20 2607);
PAINT SKYBLUE (-20 2607);
DISPLAY INVISIBLE (-20 2607);
FORCEPROP 1 LAST SIZE 1B
J 0
(100 2600);
DISPLAY 1.170213 (100 2600);
PAINT AQUA (100 2600);
DISPLAY INVISIBLE (100 2600);
FORCEPROP 2 LAST CDS_LIB mstr_symbols
J 0
(25 2650);
PAINT ORANGE (25 2650);
DISPLAY INVISIBLE (25 2650);
FORCEPROP 1 LAST BODY_TYPE PLUMBING
J 0
(-20 2607);
DISPLAY 0.340426 (-20 2607);
PAINT GREEN (-20 2607);
DISPLAY INVISIBLE (-20 2607);
FORCEPROP 1 LAST PATH I64
J 0
(100 2650);
DISPLAY 0.872340 (100 2650);
PAINT AQUA (100 2650);
DISPLAY INVISIBLE (100 2650);
FORCEPROP 1 LAST HDL_POWER GND
J 0
(25 2800);
DISPLAY 1.170213 (25 2800);
PAINT GREEN (25 2800);
DISPLAY INVISIBLE (25 2800);
FORCEADD CAP..1
(-825 2850);
FORCEPROP 1 LAST LOCATION C6U10
J 0
(-775 2950);
DISPLAY 0.617021 (-775 2950);
PAINT AQUA (-775 2950);
FORCEPROP 1 LAST PART_NUMBER G10601-001
J 0
(-775 2700);
DISPLAY 0.617021 (-775 2700);
PAINT BLUE (-775 2700);
FORCEPROP 1 LAST VALUE 10UF
J 0
(-775 2900);
DISPLAY 0.617021 (-775 2900);
PAINT SKYBLUE (-775 2900);
FORCEPROP 1 LAST TOLERANCE 10%
J 0
(-775 2800);
DISPLAY 0.617021 (-775 2800);
PAINT SKYBLUE (-775 2800);
FORCEPROP 1 LAST PACK_TYPE 0805
J 0
(-775 2650);
DISPLAY 0.617021 (-775 2650);
PAINT SKYBLUE (-775 2650);
FORCEPROP 1 LAST VOLTAGE 16V
J 0
(-775 2850);
DISPLAY 0.617021 (-775 2850);
PAINT SKYBLUE (-775 2850);
FORCEPROP 1 LAST MATERIAL X7R
J 0
(-775 2750);
DISPLAY 0.617021 (-775 2750);
PAINT SKYBLUE (-775 2750);
FORCEPROP 1 LASTPIN (-825 2750) $PN 2
J 0
(-815 2730);
DISPLAY 0.617021 (-815 2730);
PAINT WHITE (-815 2730);
FORCEPROP 1 LASTPIN (-825 2950) $PN 1
J 0
(-815 2930);
DISPLAY 0.617021 (-815 2930);
PAINT WHITE (-815 2930);
FORCEPROP 2 LAST CDS_LIB mstr_discrete
J 0
(-825 2850);
PAINT ORANGE (-825 2850);
DISPLAY INVISIBLE (-825 2850);
FORCEPROP 2 LAST CDS_SEC 1
J 0
(-775 3050);
DISPLAY 1.361702 (-775 3050);
PAINT ORANGE (-775 3050);
DISPLAY INVISIBLE (-775 3050);
FORCEPROP 2 LAST $SEC 1
J 0
(-775 3050);
DISPLAY 0.914894 (-775 3050);
PAINT MONO (-775 3050);
DISPLAY INVISIBLE (-775 3050);
FORCEPROP 2 LAST CDS_LOCATION C6U10
J 0
(-775 2950);
DISPLAY 0.617021 (-775 2950);
PAINT AQUA (-775 2950);
DISPLAY INVISIBLE (-775 2950);
FORCEPROP 1 LAST PATH I65
J 0
(-775 3000);
DISPLAY 0.978723 (-775 3000);
PAINT WHITE (-775 3000);
DISPLAY INVISIBLE (-775 3000);
FORCEPROP 0 LAST ROOM PVDDQ_ABC_PWR_VR
J 0
(-775 3000);
DISPLAY 1.021277 (-775 3000);
PAINT ORANGE (-775 3000);
DISPLAY INVISIBLE (-775 3000);
FORCEADD P12V_NVDIMM_ABC..1
(-825 3025);
FORCEPROP 3 LASTPIN (-825 2975) SIG_NAME P12V_NVDIMM_ABC\g
J 0
(-815 2985);
DISPLAY 0.659574 (-815 2985);
PAINT MONO (-815 2985);
DISPLAY INVISIBLE (-815 2985);
FORCEPROP 1 LAST VOLTAGE 12.0
J 0
(-870 2982);
DISPLAY 0.340426 (-870 2982);
PAINT SKYBLUE (-870 2982);
DISPLAY INVISIBLE (-870 2982);
FORCEPROP 2 LAST CDS_LIB mstr_symbols
J 0
(-825 3025);
PAINT ORANGE (-825 3025);
DISPLAY INVISIBLE (-825 3025);
FORCEPROP 1 LAST BODY_TYPE PLUMBING
J 0
(-870 2982);
DISPLAY 0.340426 (-870 2982);
PAINT GREEN (-870 2982);
DISPLAY INVISIBLE (-870 2982);
FORCEPROP 1 LAST PATH I66
J 0
(-775 3050);
DISPLAY 0.872340 (-775 3050);
PAINT AQUA (-775 3050);
DISPLAY INVISIBLE (-775 3050);
FORCEPROP 1 LAST HDL_POWER P12V_NVDIMM_ABC
J 1
(-825 3050);
DISPLAY 0.872340 (-825 3050);
PAINT GREEN (-825 3050);
DISPLAY INVISIBLE (-825 3050);
FORCEADD CAP..1
(25 2850);
FORCEPROP 1 LAST LOCATION C4A17
J 0
(75 2950);
DISPLAY 0.617021 (75 2950);
PAINT AQUA (75 2950);
FORCEPROP 1 LAST PART_NUMBER G10601-001
J 0
(75 2700);
DISPLAY 0.617021 (75 2700);
PAINT BLUE (75 2700);
FORCEPROP 1 LAST VALUE 10UF
J 0
(75 2900);
DISPLAY 0.617021 (75 2900);
PAINT SKYBLUE (75 2900);
FORCEPROP 1 LAST TOLERANCE 10%
J 0
(75 2800);
DISPLAY 0.617021 (75 2800);
PAINT SKYBLUE (75 2800);
FORCEPROP 1 LAST PACK_TYPE 0805
J 0
(75 2650);
DISPLAY 0.617021 (75 2650);
PAINT SKYBLUE (75 2650);
FORCEPROP 1 LAST VOLTAGE 16V
J 0
(75 2850);
DISPLAY 0.617021 (75 2850);
PAINT SKYBLUE (75 2850);
FORCEPROP 1 LAST MATERIAL X7R
J 0
(75 2750);
DISPLAY 0.617021 (75 2750);
PAINT SKYBLUE (75 2750);
FORCEPROP 1 LASTPIN (25 2750) $PN 2
J 0
(35 2730);
DISPLAY 0.617021 (35 2730);
PAINT WHITE (35 2730);
FORCEPROP 1 LASTPIN (25 2950) $PN 1
J 0
(35 2930);
DISPLAY 0.617021 (35 2930);
PAINT WHITE (35 2930);
FORCEPROP 2 LAST CDS_LIB mstr_discrete
J 0
(25 2850);
PAINT ORANGE (25 2850);
DISPLAY INVISIBLE (25 2850);
FORCEPROP 2 LAST CDS_SEC 1
J 0
(75 3050);
DISPLAY 1.361702 (75 3050);
PAINT ORANGE (75 3050);
DISPLAY INVISIBLE (75 3050);
FORCEPROP 2 LAST $SEC 1
J 0
(75 3050);
DISPLAY 0.914894 (75 3050);
PAINT MONO (75 3050);
DISPLAY INVISIBLE (75 3050);
FORCEPROP 2 LAST CDS_LOCATION C4A17
J 0
(75 2950);
DISPLAY 0.617021 (75 2950);
PAINT AQUA (75 2950);
DISPLAY INVISIBLE (75 2950);
FORCEPROP 1 LAST PATH I67
J 0
(75 3000);
DISPLAY 0.978723 (75 3000);
PAINT WHITE (75 3000);
DISPLAY INVISIBLE (75 3000);
FORCEPROP 0 LAST ROOM PVDDQ_DEF_PWR_VR
J 0
(75 3000);
DISPLAY 1.021277 (75 3000);
PAINT ORANGE (75 3000);
DISPLAY INVISIBLE (75 3000);
FORCEADD P12V_NVDIMM_DEF..1
(25 3025);
FORCEPROP 3 LASTPIN (25 2975) SIG_NAME P12V_NVDIMM_DEF\g
J 0
(35 2985);
DISPLAY 0.659574 (35 2985);
PAINT MONO (35 2985);
DISPLAY INVISIBLE (35 2985);
FORCEPROP 1 LAST VOLTAGE 12.0
J 0
(-20 2982);
DISPLAY 0.340426 (-20 2982);
PAINT SKYBLUE (-20 2982);
DISPLAY INVISIBLE (-20 2982);
FORCEPROP 2 LAST CDS_LIB mstr_symbols
J 0
(25 3025);
PAINT ORANGE (25 3025);
DISPLAY INVISIBLE (25 3025);
FORCEPROP 1 LAST BODY_TYPE PLUMBING
J 0
(-20 2982);
DISPLAY 0.340426 (-20 2982);
PAINT GREEN (-20 2982);
DISPLAY INVISIBLE (-20 2982);
FORCEPROP 1 LAST PATH I68
J 0
(75 3050);
DISPLAY 0.872340 (75 3050);
PAINT AQUA (75 3050);
DISPLAY INVISIBLE (75 3050);
FORCEPROP 1 LAST HDL_POWER P12V_NVDIMM_DEF
J 1
(25 3075);
DISPLAY 0.872340 (25 3075);
PAINT GREEN (25 3075);
DISPLAY INVISIBLE (25 3075);
FORCEADD GND..1
(850 1450);
FORCEPROP 3 LASTPIN (850 1500) SIG_NAME GND\g
J 0
(860 1510);
DISPLAY 0.659574 (860 1510);
PAINT MONO (860 1510);
DISPLAY INVISIBLE (860 1510);
FORCEPROP 1 LAST VOLTAGE 0.0V
J 0
(805 1407);
DISPLAY 0.340426 (805 1407);
PAINT SKYBLUE (805 1407);
DISPLAY INVISIBLE (805 1407);
FORCEPROP 1 LAST SIZE 1B
J 0
(925 1400);
DISPLAY 1.170213 (925 1400);
PAINT AQUA (925 1400);
DISPLAY INVISIBLE (925 1400);
FORCEPROP 2 LAST CDS_LIB mstr_symbols
J 0
(850 1450);
PAINT ORANGE (850 1450);
DISPLAY INVISIBLE (850 1450);
FORCEPROP 1 LAST BODY_TYPE PLUMBING
J 0
(805 1407);
DISPLAY 0.340426 (805 1407);
PAINT GREEN (805 1407);
DISPLAY INVISIBLE (805 1407);
FORCEPROP 1 LAST PATH I69
J 0
(925 1450);
DISPLAY 0.872340 (925 1450);
PAINT AQUA (925 1450);
DISPLAY INVISIBLE (925 1450);
FORCEPROP 1 LAST HDL_POWER GND
J 0
(850 1600);
DISPLAY 1.170213 (850 1600);
PAINT GREEN (850 1600);
DISPLAY INVISIBLE (850 1600);
FORCEADD CAP..1
(850 1625);
FORCEPROP 1 LAST LOCATION C9T8
J 0
(900 1725);
DISPLAY 0.617021 (900 1725);
PAINT AQUA (900 1725);
FORCEPROP 1 LAST PART_NUMBER G10601-001
J 0
(900 1475);
DISPLAY 0.617021 (900 1475);
PAINT BLUE (900 1475);
FORCEPROP 1 LAST VALUE 10UF
J 0
(900 1675);
DISPLAY 0.617021 (900 1675);
PAINT SKYBLUE (900 1675);
FORCEPROP 1 LAST TOLERANCE 10%
J 0
(900 1575);
DISPLAY 0.617021 (900 1575);
PAINT SKYBLUE (900 1575);
FORCEPROP 1 LAST PACK_TYPE 0805
J 0
(900 1425);
DISPLAY 0.617021 (900 1425);
PAINT SKYBLUE (900 1425);
FORCEPROP 1 LAST VOLTAGE 16V
J 0
(900 1625);
DISPLAY 0.617021 (900 1625);
PAINT SKYBLUE (900 1625);
FORCEPROP 1 LAST MATERIAL X7R
J 0
(900 1525);
DISPLAY 0.617021 (900 1525);
PAINT SKYBLUE (900 1525);
FORCEPROP 1 LASTPIN (850 1525) $PN 2
J 0
(860 1505);
DISPLAY 0.617021 (860 1505);
PAINT WHITE (860 1505);
FORCEPROP 1 LASTPIN (850 1725) $PN 1
J 0
(860 1705);
DISPLAY 0.617021 (860 1705);
PAINT WHITE (860 1705);
FORCEPROP 2 LAST CDS_LIB mstr_discrete
J 0
(850 1625);
PAINT ORANGE (850 1625);
DISPLAY INVISIBLE (850 1625);
FORCEPROP 2 LAST CDS_SEC 1
J 0
(900 1825);
DISPLAY 1.361702 (900 1825);
PAINT ORANGE (900 1825);
DISPLAY INVISIBLE (900 1825);
FORCEPROP 2 LAST $SEC 1
J 0
(900 1825);
DISPLAY 0.914894 (900 1825);
PAINT MONO (900 1825);
DISPLAY INVISIBLE (900 1825);
FORCEPROP 2 LAST CDS_LOCATION C9T8
J 0
(900 1725);
DISPLAY 0.617021 (900 1725);
PAINT AQUA (900 1725);
DISPLAY INVISIBLE (900 1725);
FORCEPROP 1 LAST PATH I70
J 0
(900 1775);
DISPLAY 0.978723 (900 1775);
PAINT WHITE (900 1775);
DISPLAY INVISIBLE (900 1775);
FORCEPROP 0 LAST ROOM PVDDQ_GHJ_PWR_VR
J 0
(900 1775);
DISPLAY 1.021277 (900 1775);
PAINT ORANGE (900 1775);
DISPLAY INVISIBLE (900 1775);
FORCEADD P12V_NVDIMM_GHJ..1
(850 1800);
FORCEPROP 3 LASTPIN (850 1750) SIG_NAME P12V_NVDIMM_GHJ\g
J 0
(860 1760);
DISPLAY 0.659574 (860 1760);
PAINT MONO (860 1760);
DISPLAY INVISIBLE (860 1760);
FORCEPROP 1 LAST VOLTAGE 12.0
J 0
(805 1757);
DISPLAY 0.340426 (805 1757);
PAINT SKYBLUE (805 1757);
DISPLAY INVISIBLE (805 1757);
FORCEPROP 2 LAST CDS_LIB mstr_symbols
J 0
(850 1800);
PAINT ORANGE (850 1800);
DISPLAY INVISIBLE (850 1800);
FORCEPROP 1 LAST BODY_TYPE PLUMBING
J 0
(805 1757);
DISPLAY 0.340426 (805 1757);
PAINT GREEN (805 1757);
DISPLAY INVISIBLE (805 1757);
FORCEPROP 1 LAST PATH I71
J 0
(900 1825);
DISPLAY 0.872340 (900 1825);
PAINT AQUA (900 1825);
DISPLAY INVISIBLE (900 1825);
FORCEPROP 1 LAST HDL_POWER P12V_NVDIMM_GHJ
J 1
(850 1850);
DISPLAY 0.872340 (850 1850);
PAINT GREEN (850 1850);
DISPLAY INVISIBLE (850 1850);
FORCEADD GND..1
(850 2025);
FORCEPROP 3 LASTPIN (850 2075) SIG_NAME GND\g
J 0
(860 2085);
DISPLAY 0.659574 (860 2085);
PAINT MONO (860 2085);
DISPLAY INVISIBLE (860 2085);
FORCEPROP 1 LAST VOLTAGE 0.0V
J 0
(805 1982);
DISPLAY 0.340426 (805 1982);
PAINT SKYBLUE (805 1982);
DISPLAY INVISIBLE (805 1982);
FORCEPROP 2 LAST CDS_LIB mstr_symbols
J 0
(850 2025);
PAINT ORANGE (850 2025);
DISPLAY INVISIBLE (850 2025);
FORCEPROP 1 LAST SIZE 1B
J 0
(925 1975);
DISPLAY 1.170213 (925 1975);
PAINT AQUA (925 1975);
DISPLAY INVISIBLE (925 1975);
FORCEPROP 1 LAST BODY_TYPE PLUMBING
J 0
(805 1982);
DISPLAY 0.340426 (805 1982);
PAINT GREEN (805 1982);
DISPLAY INVISIBLE (805 1982);
FORCEPROP 1 LAST PATH I72
J 0
(925 2025);
DISPLAY 0.872340 (925 2025);
PAINT AQUA (925 2025);
DISPLAY INVISIBLE (925 2025);
FORCEPROP 1 LAST HDL_POWER GND
J 0
(850 2175);
DISPLAY 1.170213 (850 2175);
PAINT GREEN (850 2175);
DISPLAY INVISIBLE (850 2175);
FORCEADD CAP..1
(850 2200);
FORCEPROP 1 LAST LOCATION C9U11
J 0
(900 2300);
DISPLAY 0.617021 (900 2300);
PAINT AQUA (900 2300);
FORCEPROP 1 LAST PART_NUMBER G10601-001
J 0
(900 2050);
DISPLAY 0.617021 (900 2050);
PAINT BLUE (900 2050);
FORCEPROP 1 LAST VALUE 10UF
J 0
(900 2250);
DISPLAY 0.617021 (900 2250);
PAINT SKYBLUE (900 2250);
FORCEPROP 1 LAST TOLERANCE 10%
J 0
(900 2150);
DISPLAY 0.617021 (900 2150);
PAINT SKYBLUE (900 2150);
FORCEPROP 1 LAST PACK_TYPE 0805
J 0
(900 2000);
DISPLAY 0.617021 (900 2000);
PAINT SKYBLUE (900 2000);
FORCEPROP 1 LAST VOLTAGE 16V
J 0
(900 2200);
DISPLAY 0.617021 (900 2200);
PAINT SKYBLUE (900 2200);
FORCEPROP 1 LAST MATERIAL X7R
J 0
(900 2100);
DISPLAY 0.617021 (900 2100);
PAINT SKYBLUE (900 2100);
FORCEPROP 1 LASTPIN (850 2100) $PN 2
J 0
(860 2080);
DISPLAY 0.617021 (860 2080);
PAINT WHITE (860 2080);
FORCEPROP 1 LASTPIN (850 2300) $PN 1
J 0
(860 2280);
DISPLAY 0.617021 (860 2280);
PAINT WHITE (860 2280);
FORCEPROP 2 LAST CDS_LIB mstr_discrete
J 0
(850 2200);
PAINT ORANGE (850 2200);
DISPLAY INVISIBLE (850 2200);
FORCEPROP 2 LAST CDS_SEC 1
J 0
(900 2400);
DISPLAY 1.361702 (900 2400);
PAINT ORANGE (900 2400);
DISPLAY INVISIBLE (900 2400);
FORCEPROP 2 LAST $SEC 1
J 0
(900 2400);
DISPLAY 0.914894 (900 2400);
PAINT MONO (900 2400);
DISPLAY INVISIBLE (900 2400);
FORCEPROP 2 LAST CDS_LOCATION C9U11
J 0
(900 2300);
DISPLAY 0.617021 (900 2300);
PAINT AQUA (900 2300);
DISPLAY INVISIBLE (900 2300);
FORCEPROP 1 LAST PATH I73
J 0
(900 2350);
DISPLAY 0.978723 (900 2350);
PAINT WHITE (900 2350);
DISPLAY INVISIBLE (900 2350);
FORCEPROP 0 LAST ROOM PVDDQ_GHJ_PWR_VR
J 0
(900 2350);
DISPLAY 1.021277 (900 2350);
PAINT ORANGE (900 2350);
DISPLAY INVISIBLE (900 2350);
FORCEADD P12V_NVDIMM_GHJ..1
(850 2375);
FORCEPROP 3 LASTPIN (850 2325) SIG_NAME P12V_NVDIMM_GHJ\g
J 0
(860 2335);
DISPLAY 0.659574 (860 2335);
PAINT MONO (860 2335);
DISPLAY INVISIBLE (860 2335);
FORCEPROP 1 LAST VOLTAGE 12.0
J 0
(805 2332);
DISPLAY 0.340426 (805 2332);
PAINT SKYBLUE (805 2332);
DISPLAY INVISIBLE (805 2332);
FORCEPROP 2 LAST CDS_LIB mstr_symbols
J 0
(850 2375);
PAINT ORANGE (850 2375);
DISPLAY INVISIBLE (850 2375);
FORCEPROP 1 LAST BODY_TYPE PLUMBING
J 0
(805 2332);
DISPLAY 0.340426 (805 2332);
PAINT GREEN (805 2332);
DISPLAY INVISIBLE (805 2332);
FORCEPROP 1 LAST PATH I74
J 0
(900 2400);
DISPLAY 0.872340 (900 2400);
PAINT AQUA (900 2400);
DISPLAY INVISIBLE (900 2400);
FORCEPROP 1 LAST HDL_POWER P12V_NVDIMM_GHJ
J 1
(850 2425);
DISPLAY 0.872340 (850 2425);
PAINT GREEN (850 2425);
DISPLAY INVISIBLE (850 2425);
FORCEADD GND..1
(850 2675);
FORCEPROP 3 LASTPIN (850 2725) SIG_NAME GND\g
J 0
(860 2735);
DISPLAY 0.659574 (860 2735);
PAINT MONO (860 2735);
DISPLAY INVISIBLE (860 2735);
FORCEPROP 1 LAST VOLTAGE 0.0V
J 0
(805 2632);
DISPLAY 0.340426 (805 2632);
PAINT SKYBLUE (805 2632);
DISPLAY INVISIBLE (805 2632);
FORCEPROP 1 LAST SIZE 1B
J 0
(925 2625);
DISPLAY 1.170213 (925 2625);
PAINT AQUA (925 2625);
DISPLAY INVISIBLE (925 2625);
FORCEPROP 2 LAST CDS_LIB mstr_symbols
J 0
(850 2675);
PAINT ORANGE (850 2675);
DISPLAY INVISIBLE (850 2675);
FORCEPROP 1 LAST BODY_TYPE PLUMBING
J 0
(805 2632);
DISPLAY 0.340426 (805 2632);
PAINT GREEN (805 2632);
DISPLAY INVISIBLE (805 2632);
FORCEPROP 1 LAST PATH I75
J 0
(925 2675);
DISPLAY 0.872340 (925 2675);
PAINT AQUA (925 2675);
DISPLAY INVISIBLE (925 2675);
FORCEPROP 1 LAST HDL_POWER GND
J 0
(850 2825);
DISPLAY 1.170213 (850 2825);
PAINT GREEN (850 2825);
DISPLAY INVISIBLE (850 2825);
FORCEADD CAP..1
(850 2850);
FORCEPROP 1 LAST LOCATION C9U8
J 0
(900 2950);
DISPLAY 0.617021 (900 2950);
PAINT AQUA (900 2950);
FORCEPROP 1 LAST PART_NUMBER G10601-001
J 0
(900 2700);
DISPLAY 0.617021 (900 2700);
PAINT BLUE (900 2700);
FORCEPROP 1 LAST VALUE 10UF
J 0
(900 2900);
DISPLAY 0.617021 (900 2900);
PAINT SKYBLUE (900 2900);
FORCEPROP 1 LAST TOLERANCE 10%
J 0
(900 2800);
DISPLAY 0.617021 (900 2800);
PAINT SKYBLUE (900 2800);
FORCEPROP 1 LAST PACK_TYPE 0805
J 0
(900 2650);
DISPLAY 0.617021 (900 2650);
PAINT SKYBLUE (900 2650);
FORCEPROP 1 LAST VOLTAGE 16V
J 0
(900 2850);
DISPLAY 0.617021 (900 2850);
PAINT SKYBLUE (900 2850);
FORCEPROP 1 LAST MATERIAL X7R
J 0
(900 2750);
DISPLAY 0.617021 (900 2750);
PAINT SKYBLUE (900 2750);
FORCEPROP 1 LASTPIN (850 2750) $PN 2
J 0
(860 2730);
DISPLAY 0.617021 (860 2730);
PAINT WHITE (860 2730);
FORCEPROP 1 LASTPIN (850 2950) $PN 1
J 0
(860 2930);
DISPLAY 0.617021 (860 2930);
PAINT WHITE (860 2930);
FORCEPROP 2 LAST CDS_LIB mstr_discrete
J 0
(850 2850);
PAINT ORANGE (850 2850);
DISPLAY INVISIBLE (850 2850);
FORCEPROP 2 LAST CDS_SEC 1
J 0
(900 3050);
DISPLAY 1.361702 (900 3050);
PAINT ORANGE (900 3050);
DISPLAY INVISIBLE (900 3050);
FORCEPROP 2 LAST $SEC 1
J 0
(900 3050);
DISPLAY 0.914894 (900 3050);
PAINT MONO (900 3050);
DISPLAY INVISIBLE (900 3050);
FORCEPROP 2 LAST CDS_LOCATION C9U8
J 0
(900 2950);
DISPLAY 0.617021 (900 2950);
PAINT AQUA (900 2950);
DISPLAY INVISIBLE (900 2950);
FORCEPROP 1 LAST PATH I76
J 0
(900 3000);
DISPLAY 0.978723 (900 3000);
PAINT WHITE (900 3000);
DISPLAY INVISIBLE (900 3000);
FORCEPROP 0 LAST ROOM PVDDQ_GHJ_PWR_VR
J 0
(900 3000);
DISPLAY 1.021277 (900 3000);
PAINT ORANGE (900 3000);
DISPLAY INVISIBLE (900 3000);
FORCEADD P12V_NVDIMM_GHJ..1
(850 3025);
FORCEPROP 3 LASTPIN (850 2975) SIG_NAME P12V_NVDIMM_GHJ\g
J 0
(860 2985);
DISPLAY 0.659574 (860 2985);
PAINT MONO (860 2985);
DISPLAY INVISIBLE (860 2985);
FORCEPROP 1 LAST VOLTAGE 12.0
J 0
(805 2982);
DISPLAY 0.340426 (805 2982);
PAINT SKYBLUE (805 2982);
DISPLAY INVISIBLE (805 2982);
FORCEPROP 2 LAST CDS_LIB mstr_symbols
J 0
(850 3025);
PAINT ORANGE (850 3025);
DISPLAY INVISIBLE (850 3025);
FORCEPROP 1 LAST BODY_TYPE PLUMBING
J 0
(805 2982);
DISPLAY 0.340426 (805 2982);
PAINT GREEN (805 2982);
DISPLAY INVISIBLE (805 2982);
FORCEPROP 1 LAST PATH I77
J 0
(900 3050);
DISPLAY 0.872340 (900 3050);
PAINT AQUA (900 3050);
DISPLAY INVISIBLE (900 3050);
FORCEPROP 1 LAST HDL_POWER P12V_NVDIMM_GHJ
J 1
(850 3075);
DISPLAY 0.872340 (850 3075);
PAINT GREEN (850 3075);
DISPLAY INVISIBLE (850 3075);
FORCEADD GND..1
(1700 1425);
FORCEPROP 3 LASTPIN (1700 1475) SIG_NAME GND\g
J 0
(1710 1485);
DISPLAY 0.659574 (1710 1485);
PAINT MONO (1710 1485);
DISPLAY INVISIBLE (1710 1485);
FORCEPROP 1 LAST VOLTAGE 0.0V
J 0
(1655 1382);
DISPLAY 0.340426 (1655 1382);
PAINT SKYBLUE (1655 1382);
DISPLAY INVISIBLE (1655 1382);
FORCEPROP 2 LAST CDS_LIB mstr_symbols
J 0
(1700 1425);
PAINT ORANGE (1700 1425);
DISPLAY INVISIBLE (1700 1425);
FORCEPROP 1 LAST SIZE 1B
J 0
(1775 1375);
DISPLAY 1.170213 (1775 1375);
PAINT AQUA (1775 1375);
DISPLAY INVISIBLE (1775 1375);
FORCEPROP 1 LAST BODY_TYPE PLUMBING
J 0
(1655 1382);
DISPLAY 0.340426 (1655 1382);
PAINT GREEN (1655 1382);
DISPLAY INVISIBLE (1655 1382);
FORCEPROP 1 LAST PATH I78
J 0
(1775 1425);
DISPLAY 0.872340 (1775 1425);
PAINT AQUA (1775 1425);
DISPLAY INVISIBLE (1775 1425);
FORCEPROP 1 LAST HDL_POWER GND
J 0
(1700 1575);
DISPLAY 1.170213 (1700 1575);
PAINT GREEN (1700 1575);
DISPLAY INVISIBLE (1700 1575);
FORCEADD CAP..1
(1700 1625);
FORCEPROP 1 LAST LOCATION C1A4
J 0
(1750 1725);
DISPLAY 0.617021 (1750 1725);
PAINT AQUA (1750 1725);
FORCEPROP 1 LAST PART_NUMBER G10601-001
J 0
(1750 1475);
DISPLAY 0.617021 (1750 1475);
PAINT BLUE (1750 1475);
FORCEPROP 1 LAST VALUE 10UF
J 0
(1750 1675);
DISPLAY 0.617021 (1750 1675);
PAINT SKYBLUE (1750 1675);
FORCEPROP 1 LAST TOLERANCE 10%
J 0
(1750 1575);
DISPLAY 0.617021 (1750 1575);
PAINT SKYBLUE (1750 1575);
FORCEPROP 1 LAST PACK_TYPE 0805
J 0
(1750 1425);
DISPLAY 0.617021 (1750 1425);
PAINT SKYBLUE (1750 1425);
FORCEPROP 1 LAST VOLTAGE 16V
J 0
(1750 1625);
DISPLAY 0.617021 (1750 1625);
PAINT SKYBLUE (1750 1625);
FORCEPROP 1 LAST MATERIAL X7R
J 0
(1750 1525);
DISPLAY 0.617021 (1750 1525);
PAINT SKYBLUE (1750 1525);
FORCEPROP 1 LASTPIN (1700 1525) $PN 2
J 0
(1710 1505);
DISPLAY 0.617021 (1710 1505);
PAINT WHITE (1710 1505);
FORCEPROP 1 LASTPIN (1700 1725) $PN 1
J 0
(1710 1705);
DISPLAY 0.617021 (1710 1705);
PAINT WHITE (1710 1705);
FORCEPROP 2 LAST CDS_LIB mstr_discrete
J 0
(1700 1625);
PAINT ORANGE (1700 1625);
DISPLAY INVISIBLE (1700 1625);
FORCEPROP 2 LAST CDS_SEC 1
J 0
(1750 1825);
DISPLAY 1.361702 (1750 1825);
PAINT ORANGE (1750 1825);
DISPLAY INVISIBLE (1750 1825);
FORCEPROP 2 LAST $SEC 1
J 0
(1750 1825);
DISPLAY 0.914894 (1750 1825);
PAINT MONO (1750 1825);
DISPLAY INVISIBLE (1750 1825);
FORCEPROP 2 LAST CDS_LOCATION C1A4
J 0
(1750 1725);
DISPLAY 0.617021 (1750 1725);
PAINT AQUA (1750 1725);
DISPLAY INVISIBLE (1750 1725);
FORCEPROP 1 LAST PATH I79
J 0
(1750 1775);
DISPLAY 0.978723 (1750 1775);
PAINT WHITE (1750 1775);
DISPLAY INVISIBLE (1750 1775);
FORCEPROP 0 LAST ROOM PVDDQ_KLM_PWR_VR
J 0
(1750 1775);
DISPLAY 1.021277 (1750 1775);
PAINT ORANGE (1750 1775);
DISPLAY INVISIBLE (1750 1775);
FORCEADD P12V_NVDIMM_KLM..1
(1700 1800);
FORCEPROP 3 LASTPIN (1700 1750) SIG_NAME P12V_NVDIMM_KLM\g
J 0
(1710 1760);
DISPLAY 0.659574 (1710 1760);
PAINT MONO (1710 1760);
DISPLAY INVISIBLE (1710 1760);
FORCEPROP 1 LAST VOLTAGE 12.0
J 0
(1655 1757);
DISPLAY 0.340426 (1655 1757);
PAINT SKYBLUE (1655 1757);
DISPLAY INVISIBLE (1655 1757);
FORCEPROP 2 LAST CDS_LIB mstr_symbols
J 0
(1700 1800);
PAINT ORANGE (1700 1800);
DISPLAY INVISIBLE (1700 1800);
FORCEPROP 1 LAST BODY_TYPE PLUMBING
J 0
(1655 1757);
DISPLAY 0.340426 (1655 1757);
PAINT GREEN (1655 1757);
DISPLAY INVISIBLE (1655 1757);
FORCEPROP 1 LAST PATH I80
J 0
(1750 1825);
DISPLAY 0.872340 (1750 1825);
PAINT AQUA (1750 1825);
DISPLAY INVISIBLE (1750 1825);
FORCEPROP 1 LAST HDL_POWER P12V_NVDIMM_KLM
J 1
(1700 1850);
DISPLAY 0.872340 (1700 1850);
PAINT GREEN (1700 1850);
DISPLAY INVISIBLE (1700 1850);
FORCEADD GND..1
(1700 2000);
FORCEPROP 3 LASTPIN (1700 2050) SIG_NAME GND\g
J 0
(1710 2060);
DISPLAY 0.659574 (1710 2060);
PAINT MONO (1710 2060);
DISPLAY INVISIBLE (1710 2060);
FORCEPROP 1 LAST VOLTAGE 0.0V
J 0
(1655 1957);
DISPLAY 0.340426 (1655 1957);
PAINT SKYBLUE (1655 1957);
DISPLAY INVISIBLE (1655 1957);
FORCEPROP 2 LAST CDS_LIB mstr_symbols
J 0
(1700 2000);
PAINT ORANGE (1700 2000);
DISPLAY INVISIBLE (1700 2000);
FORCEPROP 1 LAST SIZE 1B
J 0
(1775 1950);
DISPLAY 1.170213 (1775 1950);
PAINT AQUA (1775 1950);
DISPLAY INVISIBLE (1775 1950);
FORCEPROP 1 LAST BODY_TYPE PLUMBING
J 0
(1655 1957);
DISPLAY 0.340426 (1655 1957);
PAINT GREEN (1655 1957);
DISPLAY INVISIBLE (1655 1957);
FORCEPROP 1 LAST PATH I81
J 0
(1775 2000);
DISPLAY 0.872340 (1775 2000);
PAINT AQUA (1775 2000);
DISPLAY INVISIBLE (1775 2000);
FORCEPROP 1 LAST HDL_POWER GND
J 0
(1700 2150);
DISPLAY 1.170213 (1700 2150);
PAINT GREEN (1700 2150);
DISPLAY INVISIBLE (1700 2150);
FORCEADD CAP..1
(1700 2200);
FORCEPROP 1 LAST LOCATION C1B7
J 0
(1750 2300);
DISPLAY 0.617021 (1750 2300);
PAINT AQUA (1750 2300);
FORCEPROP 1 LAST PART_NUMBER G10601-001
J 0
(1750 2050);
DISPLAY 0.617021 (1750 2050);
PAINT BLUE (1750 2050);
FORCEPROP 1 LAST VALUE 10UF
J 0
(1750 2250);
DISPLAY 0.617021 (1750 2250);
PAINT SKYBLUE (1750 2250);
FORCEPROP 1 LAST TOLERANCE 10%
J 0
(1750 2150);
DISPLAY 0.617021 (1750 2150);
PAINT SKYBLUE (1750 2150);
FORCEPROP 1 LAST PACK_TYPE 0805
J 0
(1750 2000);
DISPLAY 0.617021 (1750 2000);
PAINT SKYBLUE (1750 2000);
FORCEPROP 1 LAST VOLTAGE 16V
J 0
(1750 2200);
DISPLAY 0.617021 (1750 2200);
PAINT SKYBLUE (1750 2200);
FORCEPROP 1 LAST MATERIAL X7R
J 0
(1750 2100);
DISPLAY 0.617021 (1750 2100);
PAINT SKYBLUE (1750 2100);
FORCEPROP 1 LASTPIN (1700 2100) $PN 2
J 0
(1710 2080);
DISPLAY 0.617021 (1710 2080);
PAINT WHITE (1710 2080);
FORCEPROP 1 LASTPIN (1700 2300) $PN 1
J 0
(1710 2280);
DISPLAY 0.617021 (1710 2280);
PAINT WHITE (1710 2280);
FORCEPROP 2 LAST CDS_LIB mstr_discrete
J 0
(1700 2200);
PAINT ORANGE (1700 2200);
DISPLAY INVISIBLE (1700 2200);
FORCEPROP 2 LAST CDS_SEC 1
J 0
(1750 2400);
DISPLAY 1.361702 (1750 2400);
PAINT ORANGE (1750 2400);
DISPLAY INVISIBLE (1750 2400);
FORCEPROP 2 LAST $SEC 1
J 0
(1750 2400);
DISPLAY 0.914894 (1750 2400);
PAINT MONO (1750 2400);
DISPLAY INVISIBLE (1750 2400);
FORCEPROP 2 LAST CDS_LOCATION C1B7
J 0
(1750 2300);
DISPLAY 0.617021 (1750 2300);
PAINT AQUA (1750 2300);
DISPLAY INVISIBLE (1750 2300);
FORCEPROP 1 LAST PATH I82
J 0
(1750 2350);
DISPLAY 0.978723 (1750 2350);
PAINT WHITE (1750 2350);
DISPLAY INVISIBLE (1750 2350);
FORCEPROP 0 LAST ROOM PVDDQ_KLM_PWR_VR
J 0
(1750 2350);
DISPLAY 1.021277 (1750 2350);
PAINT ORANGE (1750 2350);
DISPLAY INVISIBLE (1750 2350);
FORCEADD P12V_NVDIMM_KLM..1
(1700 2375);
FORCEPROP 3 LASTPIN (1700 2325) SIG_NAME P12V_NVDIMM_KLM\g
J 0
(1710 2335);
DISPLAY 0.659574 (1710 2335);
PAINT MONO (1710 2335);
DISPLAY INVISIBLE (1710 2335);
FORCEPROP 1 LAST VOLTAGE 12.0
J 0
(1655 2332);
DISPLAY 0.340426 (1655 2332);
PAINT SKYBLUE (1655 2332);
DISPLAY INVISIBLE (1655 2332);
FORCEPROP 2 LAST CDS_LIB mstr_symbols
J 0
(1700 2375);
PAINT ORANGE (1700 2375);
DISPLAY INVISIBLE (1700 2375);
FORCEPROP 1 LAST BODY_TYPE PLUMBING
J 0
(1655 2332);
DISPLAY 0.340426 (1655 2332);
PAINT GREEN (1655 2332);
DISPLAY INVISIBLE (1655 2332);
FORCEPROP 1 LAST PATH I83
J 0
(1750 2400);
DISPLAY 0.872340 (1750 2400);
PAINT AQUA (1750 2400);
DISPLAY INVISIBLE (1750 2400);
FORCEPROP 1 LAST HDL_POWER P12V_NVDIMM_KLM
J 1
(1700 2425);
DISPLAY 0.872340 (1700 2425);
PAINT GREEN (1700 2425);
DISPLAY INVISIBLE (1700 2425);
FORCEADD GND..1
(1700 2650);
FORCEPROP 3 LASTPIN (1700 2700) SIG_NAME GND\g
J 0
(1710 2710);
DISPLAY 0.659574 (1710 2710);
PAINT MONO (1710 2710);
DISPLAY INVISIBLE (1710 2710);
FORCEPROP 1 LAST VOLTAGE 0.0V
J 0
(1655 2607);
DISPLAY 0.340426 (1655 2607);
PAINT SKYBLUE (1655 2607);
DISPLAY INVISIBLE (1655 2607);
FORCEPROP 2 LAST CDS_LIB mstr_symbols
J 0
(1700 2650);
PAINT ORANGE (1700 2650);
DISPLAY INVISIBLE (1700 2650);
FORCEPROP 1 LAST SIZE 1B
J 0
(1775 2600);
DISPLAY 1.170213 (1775 2600);
PAINT AQUA (1775 2600);
DISPLAY INVISIBLE (1775 2600);
FORCEPROP 1 LAST BODY_TYPE PLUMBING
J 0
(1655 2607);
DISPLAY 0.340426 (1655 2607);
PAINT GREEN (1655 2607);
DISPLAY INVISIBLE (1655 2607);
FORCEPROP 1 LAST PATH I84
J 0
(1775 2650);
DISPLAY 0.872340 (1775 2650);
PAINT AQUA (1775 2650);
DISPLAY INVISIBLE (1775 2650);
FORCEPROP 1 LAST HDL_POWER GND
J 0
(1700 2800);
DISPLAY 1.170213 (1700 2800);
PAINT GREEN (1700 2800);
DISPLAY INVISIBLE (1700 2800);
FORCEADD CAP..1
(1700 2850);
FORCEPROP 1 LAST LOCATION C1A16
J 0
(1750 2950);
DISPLAY 0.617021 (1750 2950);
PAINT AQUA (1750 2950);
FORCEPROP 1 LAST PART_NUMBER G10601-001
J 0
(1750 2700);
DISPLAY 0.617021 (1750 2700);
PAINT BLUE (1750 2700);
FORCEPROP 1 LAST VALUE 10UF
J 0
(1750 2900);
DISPLAY 0.617021 (1750 2900);
PAINT SKYBLUE (1750 2900);
FORCEPROP 1 LAST TOLERANCE 10%
J 0
(1750 2800);
DISPLAY 0.617021 (1750 2800);
PAINT SKYBLUE (1750 2800);
FORCEPROP 1 LAST PACK_TYPE 0805
J 0
(1750 2650);
DISPLAY 0.617021 (1750 2650);
PAINT SKYBLUE (1750 2650);
FORCEPROP 1 LAST VOLTAGE 16V
J 0
(1750 2850);
DISPLAY 0.617021 (1750 2850);
PAINT SKYBLUE (1750 2850);
FORCEPROP 1 LAST MATERIAL X7R
J 0
(1750 2750);
DISPLAY 0.617021 (1750 2750);
PAINT SKYBLUE (1750 2750);
FORCEPROP 1 LASTPIN (1700 2750) $PN 2
J 0
(1710 2730);
DISPLAY 0.617021 (1710 2730);
PAINT WHITE (1710 2730);
FORCEPROP 1 LASTPIN (1700 2950) $PN 1
J 0
(1710 2930);
DISPLAY 0.617021 (1710 2930);
PAINT WHITE (1710 2930);
FORCEPROP 2 LAST CDS_LIB mstr_discrete
J 0
(1700 2850);
PAINT ORANGE (1700 2850);
DISPLAY INVISIBLE (1700 2850);
FORCEPROP 2 LAST CDS_SEC 1
J 0
(1750 3050);
DISPLAY 1.361702 (1750 3050);
PAINT ORANGE (1750 3050);
DISPLAY INVISIBLE (1750 3050);
FORCEPROP 2 LAST $SEC 1
J 0
(1750 3050);
DISPLAY 0.914894 (1750 3050);
PAINT MONO (1750 3050);
DISPLAY INVISIBLE (1750 3050);
FORCEPROP 2 LAST CDS_LOCATION C1A16
J 0
(1750 2950);
DISPLAY 0.617021 (1750 2950);
PAINT AQUA (1750 2950);
DISPLAY INVISIBLE (1750 2950);
FORCEPROP 1 LAST PATH I85
J 0
(1750 3000);
DISPLAY 0.978723 (1750 3000);
PAINT WHITE (1750 3000);
DISPLAY INVISIBLE (1750 3000);
FORCEPROP 0 LAST ROOM PVDDQ_KLM_PWR_VR
J 0
(1750 3000);
DISPLAY 1.021277 (1750 3000);
PAINT ORANGE (1750 3000);
DISPLAY INVISIBLE (1750 3000);
FORCEADD P12V_NVDIMM_KLM..1
(1700 3025);
FORCEPROP 3 LASTPIN (1700 2975) SIG_NAME P12V_NVDIMM_KLM\g
J 0
(1710 2985);
DISPLAY 0.659574 (1710 2985);
PAINT MONO (1710 2985);
DISPLAY INVISIBLE (1710 2985);
FORCEPROP 1 LAST VOLTAGE 12.0
J 0
(1655 2982);
DISPLAY 0.340426 (1655 2982);
PAINT SKYBLUE (1655 2982);
DISPLAY INVISIBLE (1655 2982);
FORCEPROP 2 LAST CDS_LIB mstr_symbols
J 0
(1700 3025);
PAINT ORANGE (1700 3025);
DISPLAY INVISIBLE (1700 3025);
FORCEPROP 1 LAST BODY_TYPE PLUMBING
J 0
(1655 2982);
DISPLAY 0.340426 (1655 2982);
PAINT GREEN (1655 2982);
DISPLAY INVISIBLE (1655 2982);
FORCEPROP 1 LAST PATH I86
J 0
(1750 3050);
DISPLAY 0.872340 (1750 3050);
PAINT AQUA (1750 3050);
DISPLAY INVISIBLE (1750 3050);
FORCEPROP 1 LAST HDL_POWER P12V_NVDIMM_KLM
J 1
(1700 3075);
DISPLAY 0.872340 (1700 3075);
PAINT GREEN (1700 3075);
DISPLAY INVISIBLE (1700 3075);
FORCEADD MAX9634..1
(-3800 4425);
FORCEPROP 1 LAST LOCATION U4F1
J 0
(-4150 4775);
DISPLAY 0.617021 (-4150 4775);
PAINT AQUA (-4150 4775);
FORCEPROP 1 LAST PART_NUMBER H35789-001
J 0
(-4150 4125);
DISPLAY 0.617021 (-4150 4125);
PAINT BLUE (-4150 4125);
FORCEPROP 1 LAST MATERIAL IC
J 0
(-4150 4725);
DISPLAY 0.617021 (-4150 4725);
PAINT SKYBLUE (-4150 4725);
FORCEPROP 2 LASTPIN (-4200 4475) $PN 5
J 2
(-4210 4485);
DISPLAY 0.617021 (-4210 4485);
PAINT ORANGE (-4210 4485);
FORCEPROP 2 LASTPIN (-4200 4425) $PN 4
J 2
(-4210 4435);
DISPLAY 0.617021 (-4210 4435);
PAINT ORANGE (-4210 4435);
FORCEPROP 2 LASTPIN (-3400 4475) $PN 3
J 0
(-3390 4485);
DISPLAY 0.617021 (-3390 4485);
PAINT ORANGE (-3390 4485);
FORCEPROP 2 LASTPIN (-3400 4375) $PN 1
J 0
(-3390 4385);
DISPLAY 0.617021 (-3390 4385);
PAINT ORANGE (-3390 4385);
FORCEPROP 2 LASTPIN (-3400 4325) $PN 2
J 0
(-3390 4335);
DISPLAY 0.617021 (-3390 4335);
PAINT ORANGE (-3390 4335);
FORCEPROP 1 LAST PACK_TYPE SOT
J 0
(-4150 4825);
PAINT SKYBLUE (-4150 4825);
DISPLAY INVISIBLE (-4150 4825);
FORCEPROP 2 LAST SEC_TYPE SOT
J 0
(-4150 4825);
DISPLAY 1.021277 (-4150 4825);
PAINT ORANGE (-4150 4825);
DISPLAY INVISIBLE (-4150 4825);
FORCEPROP 0 LAST BOM_COST PVDDQ_ABC_VR
J 0
(-4150 4975);
DISPLAY 1.021277 (-4150 4975);
PAINT ORANGE (-4150 4975);
DISPLAY INVISIBLE (-4150 4975);
FORCEPROP 2 LAST CDS_LIB mstr_vreg
J 0
(-3800 4425);
PAINT ORANGE (-3800 4425);
DISPLAY INVISIBLE (-3800 4425);
FORCEPROP 2 LAST SEC 1
J 0
(-4150 4825);
DISPLAY 0.680851 (-4150 4825);
PAINT MONO (-4150 4825);
DISPLAY INVISIBLE (-4150 4825);
FORCEPROP 2 LAST CDS_LOCATION U4F1
J 0
(-4150 4775);
DISPLAY 0.617021 (-4150 4775);
PAINT AQUA (-4150 4775);
DISPLAY INVISIBLE (-4150 4775);
FORCEPROP 1 LAST PATH I97
J 0
(-3825 4725);
PAINT GREEN (-3825 4725);
DISPLAY INVISIBLE (-3825 4725);
FORCEPROP 2 LAST ROOM PVDDQ_ABC_PWR_VR
J 0
(-4150 4875);
DISPLAY 1.021277 (-4150 4875);
PAINT ORANGE (-4150 4875);
DISPLAY INVISIBLE (-4150 4875);
FORCEADD RES..1
(-4575 4750);
FORCEPROP 1 LAST LOCATION R4F2
J 0
(-4625 4800);
DISPLAY 0.617021 (-4625 4800);
PAINT AQUA (-4625 4800);
FORCEPROP 1 LAST PART_NUMBER G52199-004
J 0
(-4625 4850);
DISPLAY 0.617021 (-4625 4850);
PAINT BLUE (-4625 4850);
FORCEPROP 1 LAST VALUE 0.002
J 2
(-4600 4650);
DISPLAY 0.617021 (-4600 4650);
PAINT SKYBLUE (-4600 4650);
FORCEPROP 1 LAST TOLERANCE 1%
J 0
(-4575 4650);
DISPLAY 0.617021 (-4575 4650);
PAINT SKYBLUE (-4575 4650);
FORCEPROP 1 LAST PACK_TYPE 1206
J 0
(-4475 4600);
DISPLAY 0.617021 (-4475 4600);
PAINT SKYBLUE (-4475 4600);
FORCEPROP 1 LAST MATERIAL CHIP
J 0
(-4575 4600);
DISPLAY 0.617021 (-4575 4600);
PAINT SKYBLUE (-4575 4600);
FORCEPROP 1 LAST WATTAGE 1W
J 2
(-4600 4600);
DISPLAY 0.617021 (-4600 4600);
PAINT SKYBLUE (-4600 4600);
FORCEPROP 1 LASTPIN (-4475 4750) $PN 2
J 0
(-4513 4762);
DISPLAY 0.617021 (-4513 4762);
PAINT ORANGE (-4513 4762);
FORCEPROP 1 LASTPIN (-4675 4750) $PN 1
J 0
(-4663 4762);
DISPLAY 0.617021 (-4663 4762);
PAINT ORANGE (-4663 4762);
FORCEPROP 2 LAST SEC_TYPE 1206
J 0
(-4625 4950);
DISPLAY 1.021277 (-4625 4950);
PAINT ORANGE (-4625 4950);
DISPLAY INVISIBLE (-4625 4950);
FORCEPROP 2 LAST BOM_COST PVDDQ_ABC_VR
J 0
(-4625 4950);
DISPLAY 1.361702 (-4625 4950);
PAINT ORANGE (-4625 4950);
DISPLAY INVISIBLE (-4625 4950);
FORCEPROP 2 LAST CDS_LIB mstr_discrete
J 0
(-4575 4750);
PAINT ORANGE (-4575 4750);
DISPLAY INVISIBLE (-4575 4750);
FORCEPROP 2 LAST SEC 1
J 0
(-4625 4950);
DISPLAY 0.680851 (-4625 4950);
PAINT MONO (-4625 4950);
DISPLAY INVISIBLE (-4625 4950);
FORCEPROP 2 LAST CDS_LOCATION R4F2
J 0
(-4625 4800);
DISPLAY 0.617021 (-4625 4800);
PAINT AQUA (-4625 4800);
DISPLAY INVISIBLE (-4625 4800);
FORCEPROP 1 LAST PATH I99
J 0
(-4625 4900);
DISPLAY 0.978723 (-4625 4900);
PAINT WHITE (-4625 4900);
DISPLAY INVISIBLE (-4625 4900);
FORCEPROP 2 LAST ROOM PVDDQ_ABC_PWR_VR
J 0
(-4625 4850);
DISPLAY 1.361702 (-4625 4850);
PAINT ORANGE (-4625 4850);
DISPLAY INVISIBLE (-4625 4850);
FORCEADD CAD_NOTE..1
(-1050 3300);
FORCEPROP 2 LAST L1 PLACE AT THE CENTER OF EACH DIMM CHANNEL. CLOSE TO THE 12V PINS OF NVDIMM CONNECTOR
J 0
(-1200 3175);
DISPLAY 0.829787 (-1200 3175);
PAINT WHITE (-1200 3175);
FORCEPROP 2 LAST CDS_LIB mstr_symbols
J 0
(-1050 3300);
PAINT MONO (-1050 3300);
DISPLAY INVISIBLE (-1050 3300);
FORCEPROP 1 LAST COMMENT_BODY TRUE
J 0
(-1025 3400);
DISPLAY 1.319149 (-1025 3400);
PAINT ORANGE (-1025 3400);
DISPLAY INVISIBLE (-1025 3400);
FORCEADD INTEL_CORP_BPAGE..1
(2650 500);
FORCEPROP 1 LAST CDS_CON_LAST_MODIFIED Tue Dec 01 11:52:19 2015
J 0
(1225 825);
PAINT ORANGE (1225 825);
DISPLAY INVISIBLE (1225 825);
FORCEPROP 1 LAST CUSTOM_TXT_CDS <CURRENT_DESIGN_SHEET> OF <TOTAL_DESIGN_SHEETS>
J 0
(2150 525);
PAINT GREEN (2150 525);
FORCEPROP 1 LAST CUSTOM_TXT_CDS <CON_LAST_MODIFIED>
J 0
(725 850);
PAINT GREEN (725 850);
FORCEPROP 2 LAST CUSTOM_TXT_CDS <XR_PAGE_TITLE>
J 0
(-5240 5750);
DISPLAY 0.638298 (-5240 5750);
PAINT PINK (-5240 5750);
DISPLAY INVISIBLE (-5240 5750);
FORCEPROP 1 LAST SCH_ADDRESS3 Santa Clara, CA 95052-8119
J 0
(-1325 525);
DISPLAY 0.617021 (-1325 525);
PAINT GREEN (-1325 525);
FORCEPROP 1 LAST SCH_ADDRESS2 P.O. BOX 58119
J 0
(-1325 575);
DISPLAY 0.617021 (-1325 575);
PAINT GREEN (-1325 575);
FORCEPROP 1 LAST SCH_ADDRESS1 2200 Mission College Blvd.
J 0
(-1325 625);
DISPLAY 0.617021 (-1325 625);
PAINT GREEN (-1325 625);
FORCEPROP 1 LAST SCH_TITLE POWER MISC: RAPL RESISTOR
J 0
(-5300 550);
DISPLAY 1.212766 (-5300 550);
PAINT ORANGE (-5300 550);
FORCEPROP 1 LAST SCH_NUMBER H4694802
J 0
(1350 650);
DISPLAY 1.212766 (1350 650);
PAINT YELLOW (1350 650);
FORCEPROP 1 LAST SCH_DEPT BESD
J 1
(-1800 600);
DISPLAY 1.212766 (-1800 600);
PAINT YELLOW (-1800 600);
FORCEPROP 1 LAST SCH_REV 2.420
J 0
(2400 650);
DISPLAY 0.978723 (2400 650);
PAINT YELLOW (2400 650);
FORCEPROP 2 LAST PAGE_BORDER TRUE
J 0
(-5240 5750);
DISPLAY 0.851064 (-5240 5750);
PAINT PINK (-5240 5750);
DISPLAY INVISIBLE (-5240 5750);
FORCEPROP 2 LAST CDS_LIB mstr_symbols
J 0
(2650 500);
PAINT MONO (2650 500);
DISPLAY INVISIBLE (2650 500);
FORCEPROP 1 LAST COMMENT_BODY TRUE
J 0
(2662 512);
DISPLAY 0.468085 (2662 512);
PAINT GREEN (2662 512);
DISPLAY INVISIBLE (2662 512);
FORCEPROP 2 LAST CDS_XR_PAGE_TITLE CR-197 : @BASEBOARD_FAB2_LIB.BASEBOARD_FAB2(SCH_1):PAGE197
J 0
(-5240 5750);
DISPLAY 0.638298 (-5240 5750);
PAINT PINK (-5240 5750);
DISPLAY INVISIBLE (-5240 5750);
WIRE 16 -1 (-4800 4425)(-4200 4425);
WIRE 16 -1 (-4800 4750)(-4800 4425);
WIRE 16 -1 (-4675 4750)(-4800 4750);
WIRE 16 -1 (-4875 4750)(-4800 4750);
WIRE 16 -1 (-4875 4875)(-4875 4750);
WIRE 16 -1 (-3400 4375)(-3250 4375);
WIRE 16 -1 (-3250 4375)(-3250 4325);
WIRE 16 -1 (-3400 4325)(-3250 4325);
WIRE 16 -1 (-3250 4325)(-3250 4200);
WIRE 16 -1 (-3400 2925)(-3250 2925);
WIRE 16 -1 (-3250 2925)(-3250 2875);
WIRE 16 -1 (-3400 2875)(-3250 2875);
WIRE 16 -1 (-3250 2875)(-3250 2750);
WIRE 16 -1 (-4800 3300)(-4800 2975);
WIRE 16 -1 (-4675 3300)(-4800 3300);
WIRE 16 -1 (-4875 3300)(-4800 3300);
WIRE 16 -1 (-4800 2975)(-4200 2975);
WIRE 16 -1 (-4875 3425)(-4875 3300);
WIRE 16 -1 (-3400 1500)(-3250 1500);
WIRE 16 -1 (-3250 1500)(-3250 1450);
WIRE 16 -1 (-3400 1450)(-3250 1450);
WIRE 16 -1 (-3250 1450)(-3250 1325);
WIRE 16 -1 (-4800 1550)(-4200 1550);
WIRE 16 -1 (-4800 1875)(-4800 1550);
WIRE 16 -1 (-4675 1875)(-4800 1875);
WIRE 16 -1 (-4875 1875)(-4800 1875);
WIRE 16 -1 (-4875 2000)(-4875 1875);
WIRE 16 -1 (425 4375)(575 4375);
WIRE 16 -1 (575 4375)(575 4325);
WIRE 16 -1 (425 4325)(575 4325);
WIRE 16 -1 (575 4325)(575 4200);
WIRE 16 -1 (-975 4425)(-375 4425);
WIRE 16 -1 (-975 4750)(-975 4425);
WIRE 16 -1 (-850 4750)(-975 4750);
WIRE 16 -1 (-1050 4750)(-975 4750);
WIRE 16 -1 (-1050 4875)(-1050 4750);
WIRE 16 -1 (-4275 4750)(-4275 4475);
WIRE 16 -1 (-4200 4750)(-4275 4750);
WIRE 16 -1 (-4275 4750)(-4475 4750);
WIRE 16 -1 (-4275 4475)(-4200 4475);
WIRE 16 -1 (-4200 4875)(-4200 4750);
WIRE 16 -1 (-4275 3300)(-4275 3025);
WIRE 16 -1 (-4200 3300)(-4275 3300);
WIRE 16 -1 (-4275 3300)(-4475 3300);
WIRE 16 -1 (-4275 3025)(-4200 3025);
WIRE 16 -1 (-4200 3425)(-4200 3300);
WIRE 16 -1 (-450 4750)(-450 4475);
WIRE 16 -1 (-375 4750)(-450 4750);
WIRE 16 -1 (-450 4750)(-650 4750);
WIRE 16 -1 (-450 4475)(-375 4475);
WIRE 16 -1 (-375 4875)(-375 4750);
WIRE 16 -1 (-4275 1875)(-4275 1600);
WIRE 16 -1 (-4200 1875)(-4275 1875);
WIRE 16 -1 (-4275 1875)(-4475 1875);
WIRE 16 -1 (-4275 1600)(-4200 1600);
WIRE 16 -1 (-4200 2000)(-4200 1875);
WIRE 16 -1 (-825 1475)(-825 1525);
WIRE 16 -1 (-825 1750)(-825 1725);
WIRE 16 -1 (-825 2050)(-825 2100);
WIRE 16 -1 (-825 2325)(-825 2300);
WIRE 16 -1 (-825 2700)(-825 2750);
WIRE 16 -1 (25 1475)(25 1525);
WIRE 16 -1 (25 1750)(25 1725);
WIRE 16 -1 (25 2050)(25 2100);
WIRE 16 -1 (25 2325)(25 2300);
WIRE 16 -1 (25 2700)(25 2750);
WIRE 16 -1 (-825 2975)(-825 2950);
WIRE 16 -1 (25 2975)(25 2950);
WIRE 16 -1 (850 1500)(850 1525);
WIRE 16 -1 (850 1750)(850 1725);
WIRE 16 -1 (850 2075)(850 2100);
WIRE 16 -1 (850 2325)(850 2300);
WIRE 16 -1 (850 2725)(850 2750);
WIRE 16 -1 (850 2975)(850 2950);
WIRE 16 -1 (1700 1475)(1700 1525);
WIRE 16 -1 (1700 1750)(1700 1725);
WIRE 16 -1 (1700 2050)(1700 2100);
WIRE 16 -1 (1700 2325)(1700 2300);
WIRE 16 -1 (1700 2700)(1700 2750);
WIRE 16 -1 (1700 2975)(1700 2950);
WIRE 16 -1 (-3400 1600)(-2875 1600);
FORCEPROP 2 LAST SIG_NAME VR_PVDDQ_GHJ_AIINSEN_R
J 0
(-3335 1610);
DISPLAY 0.617021 (-3335 1610);
PAINT ORANGE (-3335 1610);
FORCEPROP 2 LASTPROP $XRERR UNIQUE?
J 0
(-3575 1610);
DISPLAY 0.638298 (-3575 1610);
PAINT MONO (-3575 1610);
DISPLAY INVISIBLE (-3575 1610);
WIRE 16 -1 (-3400 3025)(-2875 3025);
FORCEPROP 2 LAST SIG_NAME VR_PVDDQ_DEF_AIINSEN_R
J 0
(-3335 3035);
DISPLAY 0.617021 (-3335 3035);
PAINT ORANGE (-3335 3035);
FORCEPROP 2 LASTPROP $XRERR UNIQUE?
J 0
(-3575 3035);
DISPLAY 0.638298 (-3575 3035);
PAINT MONO (-3575 3035);
DISPLAY INVISIBLE (-3575 3035);
WIRE 16 -1 (-2675 3025)(-1925 3025);
FORCEPROP 2 LAST SIG_NAME VR_PVDDQ_DEF_AIINSEN
J 0
(-2510 3035);
DISPLAY 0.617021 (-2510 3035);
PAINT ORANGE (-2510 3035);
WIRE 16 -1 (-1925 1600)(-2675 1600);
FORCEPROP 2 LAST SIG_NAME VR_PVDDQ_GHJ_AIINSEN
J 0
(-2510 1610);
DISPLAY 0.617021 (-2510 1610);
PAINT ORANGE (-2510 1610);
WIRE 16 -1 (-3400 4475)(-2875 4475);
FORCEPROP 2 LAST SIG_NAME VR_PVDDQ_ABC_AIINSEN_R
J 0
(-3335 4485);
DISPLAY 0.617021 (-3335 4485);
PAINT ORANGE (-3335 4485);
FORCEPROP 2 LASTPROP $XRERR UNIQUE?
J 0
(-3575 4485);
DISPLAY 0.638298 (-3575 4485);
PAINT MONO (-3575 4485);
DISPLAY INVISIBLE (-3575 4485);
WIRE 16 -1 (-2675 4475)(-1925 4475);
FORCEPROP 2 LAST SIG_NAME VR_PVDDQ_ABC_AIINSEN
J 0
(-2510 4485);
DISPLAY 0.617021 (-2510 4485);
PAINT ORANGE (-2510 4485);
WIRE 16 -1 (425 4475)(950 4475);
FORCEPROP 2 LAST SIG_NAME VR_PVDDQ_KLM_AIINSEN_R
J 0
(490 4485);
DISPLAY 0.617021 (490 4485);
PAINT ORANGE (490 4485);
FORCEPROP 2 LASTPROP $XRERR UNIQUE?
J 0
(250 4485);
DISPLAY 0.638298 (250 4485);
PAINT MONO (250 4485);
DISPLAY INVISIBLE (250 4485);
WIRE 16 -1 (1900 4475)(1150 4475);
FORCEPROP 2 LAST SIG_NAME VR_PVDDQ_KLM_AIINSEN
J 0
(1315 4485);
DISPLAY 0.617021 (1315 4485);
PAINT ORANGE (1315 4485);
DOT 1 (575 4325);
DOT 1 (-450 4750);
DOT 1 (-975 4750);
DOT 1 (-3250 4325);
DOT 1 (-3250 2875);
DOT 1 (-3250 1450);
DOT 1 (-4275 4750);
DOT 1 (-4800 4750);
DOT 1 (-4275 3300);
DOT 1 (-4800 3300);
DOT 1 (-4275 1875);
DOT 1 (-4800 1875);
FORCENOTE
ROOM=PVDDQ_ABC_PWR_VR
(-4800 3825) 0;
DISPLAY LEFT (-4800 3825);
DISPLAY 1.574468 (-4800 3825);
PAINT PURPLE (-4800 3825);
FORCENOTE
ROOM=PVDDQ_GHJ_PWR_VR
(-4800 950) 0;
DISPLAY LEFT (-4800 950);
DISPLAY 1.574468 (-4800 950);
PAINT PURPLE (-4800 950);
FORCENOTE
ROOM=PVDDQ_DEF_PWR_VR
(-4800 2375) 0;
DISPLAY LEFT (-4800 2375);
DISPLAY 1.574468 (-4800 2375);
PAINT PURPLE (-4800 2375);
FORCENOTE
BOM_COST=PVDDQ_ABC_VR
(-4800 3950) 0;
DISPLAY LEFT (-4800 3950);
DISPLAY 1.574468 (-4800 3950);
PAINT PURPLE (-4800 3950);
FORCENOTE
BOM_COST=PVDDQ_GHJ_VR
(-4800 1075) 0;
DISPLAY LEFT (-4800 1075);
DISPLAY 1.574468 (-4800 1075);
PAINT PURPLE (-4800 1075);
FORCENOTE
BOM_COST=PVDDQ_DEF_VR
(-4800 2500) 0;
DISPLAY LEFT (-4800 2500);
DISPLAY 1.574468 (-4800 2500);
PAINT PURPLE (-4800 2500);
FORCENOTE
RAPL RESISTOR CH GHJ
(-4008 1896) 0;
DISPLAY LEFT (-4008 1896);
DISPLAY 1.723404 (-4008 1896);
PAINT PURPLE (-4008 1896);
FORCENOTE
RAPL RESISTOR CH DEF
(-4008 3321) 0;
DISPLAY LEFT (-4008 3321);
DISPLAY 1.723404 (-4008 3321);
PAINT PURPLE (-4008 3321);
FORCENOTE
RAPL RESISTOR CH ABC
(-4008 4771) 0;
DISPLAY LEFT (-4008 4771);
DISPLAY 1.723404 (-4008 4771);
PAINT PURPLE (-4008 4771);
FORCENOTE
ROOM=PVDDQ_KLM_PWR_VR
(-975 3825) 0;
DISPLAY LEFT (-975 3825);
DISPLAY 1.574468 (-975 3825);
PAINT PURPLE (-975 3825);
FORCENOTE
RAPL RESISTOR CH KLM
(-183 4771) 0;
DISPLAY LEFT (-183 4771);
DISPLAY 1.723404 (-183 4771);
PAINT PURPLE (-183 4771);
FORCENOTE
BOM_COST=PVDDQ_KLM_VR
(-975 3950) 0;
DISPLAY LEFT (-975 3950);
DISPLAY 1.574468 (-975 3950);
PAINT PURPLE (-975 3950);
QUIT
